FILE_TYPE = CONNECTIVITY;
{Allegro Design Entry HDL 17.4-2019 S026 (4007227) 1/17/2022}
"PAGE_NUMBER" = 355;
0"NC";
1"P5E_CPU1_G1_TX_DP<7:0>";
2"P5E_CPU1_G1_TX_C_DP<15:8>";
3"P5E_CPU1_G1_TX_C_DN<15:8>";
4"P5E_CPU1_G1_TX_C_DP<7:0>";
5"P5E_CPU1_G1_TX_DN<15:8>";
6"P5E_CPU1_G1_TX_DP<15:8>";
7"P5E_CPU1_G1_TX_C_DN<7:0>";
8"P5E_CPU1_G1_TX_DN<7:0>";
9"P3E_CPU1_P4_TX_C_DP<3:0>";
10"P3E_CPU1_P4_TX_C_DN<3:0>";
11"P3E_CPU1_P4_TX_DP<3:0>";
12"P3E_CPU1_P4_TX_DN<3:0>";
13"P5E_CPU1_P3_TX_C_DP<15:8>";
14"P5E_CPU1_P3_TX_C_DN<15:8>";
15"P5E_CPU1_P3_TX_DP<15:8>";
16"P5E_CPU1_P3_TX_DN<15:8>";
17"P5E_CPU1_P3_TX_C_DP<7:0>";
18"P5E_CPU1_P3_TX_C_DN<7:0>";
19"P3E_CPU0_P4_TX_C_DP<3:0>";
20"P3E_CPU0_P4_TX_C_DN<3:0>";
21"P3E_CPU0_P4_TX_DP<3:0>";
22"P5E_CPU1_P3_TX_DN<7:0>";
23"P5E_CPU1_P3_TX_DP<7:0>";
24"P3E_CPU0_P4_TX_DN<3:0>";
25"P3E_CPU0_P4_TX_DN<3>";
26"P3E_CPU0_P4_TX_DN<2>";
27"P3E_CPU0_P4_TX_DN<1>";
28"P3E_CPU0_P4_TX_DP<2>";
29"P3E_CPU0_P4_TX_DP<1>";
30"P3E_CPU0_P4_TX_DP<3>";
31"P3E_CPU0_P4_TX_C_DN<3>";
32"P3E_CPU0_P4_TX_C_DP<3>";
33"P3E_CPU0_P4_TX_C_DN<2>";
34"P3E_CPU0_P4_TX_C_DP<2>";
35"P3E_CPU0_P4_TX_C_DN<1>";
36"P3E_CPU0_P4_TX_C_DP<1>";
37"P3E_CPU0_P4_TX_DN<0>";
38"P5E_CPU1_P3_TX_DN<4>";
39"P5E_CPU1_P3_TX_DN<12>";
40"P5E_CPU1_P3_TX_DN<11>";
41"P5E_CPU1_P3_TX_DP<12>";
42"P5E_CPU1_P3_TX_DP<11>";
43"P5E_CPU1_P3_TX_DN<9>";
44"P5E_CPU1_P3_TX_DN<10>";
45"P5E_CPU1_P3_TX_DN<8>";
46"P5E_CPU1_P3_TX_DP<10>";
47"P5E_CPU1_P3_TX_DP<8>";
48"P5E_CPU1_P3_TX_DP<9>";
49"P5E_CPU1_P3_TX_DP<7>";
50"P5E_CPU1_P3_TX_DP<0>";
51"P5E_CPU1_P3_TX_DP<1>";
52"P5E_CPU1_P3_TX_DN<0>";
53"P5E_CPU1_P3_TX_DN<1>";
54"P5E_CPU1_P3_TX_DP<2>";
55"P5E_CPU1_P3_TX_DP<3>";
56"P5E_CPU1_P3_TX_DP<4>";
57"P5E_CPU1_P3_TX_DN<2>";
58"P5E_CPU1_P3_TX_DN<3>";
59"P5E_CPU1_P3_TX_DP<5>";
60"P5E_CPU1_P3_TX_DP<6>";
61"P5E_CPU1_P3_TX_DN<5>";
62"P5E_CPU1_P3_TX_DN<6>";
63"P5E_CPU1_P3_TX_DN<7>";
64"P3E_CPU0_P4_TX_DP<0>";
65"P3E_CPU0_P4_TX_C_DN<0>";
66"P3E_CPU0_P4_TX_C_DP<0>";
67"P5E_CPU1_P3_TX_C_DP<0>";
68"P5E_CPU1_P3_TX_C_DN<0>";
69"P5E_CPU1_P3_TX_C_DP<1>";
70"P5E_CPU1_P3_TX_C_DP<2>";
71"P5E_CPU1_P3_TX_C_DN<1>";
72"P5E_CPU1_P3_TX_C_DN<2>";
73"P5E_CPU1_P3_TX_C_DP<12>";
74"P5E_CPU1_P3_TX_C_DN<12>";
75"P5E_CPU1_P3_TX_C_DP<11>";
76"P5E_CPU1_P3_TX_C_DN<11>";
77"P5E_CPU1_P3_TX_C_DN<9>";
78"P5E_CPU1_P3_TX_C_DP<10>";
79"P5E_CPU1_P3_TX_C_DN<10>";
80"P5E_CPU1_P3_TX_C_DN<8>";
81"P5E_CPU1_P3_TX_C_DP<9>";
82"P5E_CPU1_P3_TX_C_DP<8>";
83"P5E_CPU1_P3_TX_C_DN<7>";
84"P5E_CPU1_P3_TX_C_DP<7>";
85"P5E_CPU1_P3_TX_C_DP<3>";
86"P5E_CPU1_P3_TX_C_DP<4>";
87"P5E_CPU1_P3_TX_C_DP<5>";
88"P5E_CPU1_P3_TX_C_DN<5>";
89"P5E_CPU1_P3_TX_C_DN<3>";
90"P5E_CPU1_P3_TX_C_DN<4>";
91"P5E_CPU1_P3_TX_C_DN<6>";
92"P5E_CPU1_P3_TX_C_DP<6>";
93"P5E_CPU1_P3_TX_DN<14>";
94"P5E_CPU1_P3_TX_DN<15>";
95"P5E_CPU1_P3_TX_DN<13>";
96"P5E_CPU1_P3_TX_DP<15>";
97"P5E_CPU1_P3_TX_DP<14>";
98"P5E_CPU1_P3_TX_DP<13>";
99"P5E_CPU1_P3_TX_C_DN<14>";
100"P5E_CPU1_P3_TX_C_DP<15>";
101"P5E_CPU1_P3_TX_C_DN<15>";
102"P5E_CPU1_P3_TX_C_DN<13>";
103"P5E_CPU1_P3_TX_C_DP<14>";
104"P5E_CPU1_P3_TX_C_DP<13>";
105"P3E_CPU1_P4_TX_DP<1>";
106"P3E_CPU1_P4_TX_DN<1>";
107"P3E_CPU1_P4_TX_DN<2>";
108"P3E_CPU1_P4_TX_DP<2>";
109"P3E_CPU1_P4_TX_DP<3>";
110"P3E_CPU1_P4_TX_DN<3>";
111"P3E_CPU1_P4_TX_C_DN<1>";
112"P3E_CPU1_P4_TX_C_DP<2>";
113"P3E_CPU1_P4_TX_C_DN<2>";
114"P3E_CPU1_P4_TX_C_DP<1>";
115"P3E_CPU1_P4_TX_C_DN<3>";
116"P3E_CPU1_P4_TX_C_DP<3>";
117"P3E_CPU1_P4_TX_DN<0>";
118"P3E_CPU1_P4_TX_DP<0>";
119"P5E_CPU1_G1_TX_DP<1>";
120"P5E_CPU1_G1_TX_DN<0>";
121"P5E_CPU1_G1_TX_DN<1>";
122"P5E_CPU1_G1_TX_DP<2>";
123"P5E_CPU1_G1_TX_DN<2>";
124"P5E_CPU1_G1_TX_DP<0>";
125"P3E_CPU1_P4_TX_C_DN<0>";
126"P3E_CPU1_P4_TX_C_DP<0>";
127"P5E_CPU1_G1_TX_C_DN<0>";
128"P5E_CPU1_G1_TX_C_DP<1>";
129"P5E_CPU1_G1_TX_C_DN<1>";
130"P5E_CPU1_G1_TX_C_DP<2>";
131"P5E_CPU1_G1_TX_C_DN<2>";
132"P5E_CPU1_G1_TX_C_DP<0>";
133"P5E_CPU1_G1_TX_DP<10>";
134"P5E_CPU1_G1_TX_DN<6>";
135"P5E_CPU1_G1_TX_DP<3>";
136"P5E_CPU1_G1_TX_DP<4>";
137"P5E_CPU1_G1_TX_DN<4>";
138"P5E_CPU1_G1_TX_DN<3>";
139"P5E_CPU1_G1_TX_DP<5>";
140"P5E_CPU1_G1_TX_DP<7>";
141"P5E_CPU1_G1_TX_DN<5>";
142"P5E_CPU1_G1_TX_DN<7>";
143"P5E_CPU1_G1_TX_DP<9>";
144"P5E_CPU1_G1_TX_DP<8>";
145"P5E_CPU1_G1_TX_DN<8>";
146"P5E_CPU1_G1_TX_DN<9>";
147"P5E_CPU1_G1_TX_DN<10>";
148"P5E_CPU1_G1_TX_DP<11>";
149"P5E_CPU1_G1_TX_DP<12>";
150"P5E_CPU1_G1_TX_DN<11>";
151"P5E_CPU1_G1_TX_DN<12>";
152"P5E_CPU1_G1_TX_C_DP<3>";
153"P5E_CPU1_G1_TX_C_DN<3>";
154"P5E_CPU1_G1_TX_C_DP<4>";
155"P5E_CPU1_G1_TX_C_DN<4>";
156"P5E_CPU1_G1_TX_C_DP<5>";
157"P5E_CPU1_G1_TX_C_DN<5>";
158"P5E_CPU1_G1_TX_C_DN<6>";
159"P5E_CPU1_G1_TX_C_DP<6>";
160"P5E_CPU1_G1_TX_C_DN<7>";
161"P5E_CPU1_G1_TX_C_DP<10>";
162"P5E_CPU1_G1_TX_C_DN<10>";
163"P5E_CPU1_G1_TX_C_DP<11>";
164"P5E_CPU1_G1_TX_C_DN<11>";
165"P5E_CPU1_G1_TX_C_DP<12>";
166"P5E_CPU1_G1_TX_C_DN<12>";
167"P5E_CPU1_G1_TX_DP<14>";
168"P5E_CPU1_G1_TX_DP<13>";
169"P5E_CPU1_G1_TX_DP<15>";
170"P5E_CPU1_G1_TX_DN<13>";
171"P5E_CPU1_G1_TX_DN<14>";
172"P5E_CPU1_G1_TX_DN<15>";
173"P5E_CPU1_G1_TX_C_DP<13>";
174"P5E_CPU1_G1_TX_C_DN<13>";
175"P5E_CPU1_G1_TX_C_DP<14>";
176"P5E_CPU1_G1_TX_C_DN<14>";
177"P5E_CPU1_G1_TX_C_DP<15>";
178"P5E_CPU1_G1_TX_C_DN<15>";
179"P5E_CPU1_G1_TX_C_DP<7>";
180"P5E_CPU1_G1_TX_C_DN<8>";
181"P5E_CPU1_G1_TX_C_DN<9>";
182"P5E_CPU1_G1_TX_C_DP<9>";
183"P5E_CPU1_G1_TX_C_DP<8>";
184"P5E_CPU1_G1_TX_DP<6>";
%"TAP"
"1","(-2350,-550)","2","standard","I1";
;
CDS_LIB"standard"
BODY_TYPE"PLUMBING"
HDL_TAP"TRUE";
"B \NAC \NWC"24;
"S \NAC"
BN"3"25;
%"Q_CAP_DIFFBUS"
"2","(-1375,-300)","2","pure_quanta","I10";
;
LOCATION"C1991"
$SEC"1"
CDS_SEC"1"
VALUE"DIFF BUS_0.22UF"
CDS_LIB"pure_quanta"
CDS_LMAN_SYM_OUTLINE"-25,50,25,-50"
PIN_NAMES_ROTATE"TRUE"
VOLTAGE"6.3V"
MATERIAL"X6S"
PACK_TYPE"C0201"
TOLERANCE"20%"
PART_NUMBER"SP_CH4221MEE01";
"2"
$PN"2"28;
"1"
$PN"1"34;
%"TAP"
"1","(-750,3050)","0","standard","I100";
;
CDS_LIB"standard"
BODY_TYPE"PLUMBING"
HDL_TAP"TRUE";
"B \NAC \NWC"13;
"S \NAC"
BN"8"82;
%"TAP"
"1","(-750,3250)","0","standard","I101";
;
CDS_LIB"standard"
BODY_TYPE"PLUMBING"
HDL_TAP"TRUE";
"B \NAC \NWC"13;
"S \NAC"
BN"9"81;
%"TAP"
"1","(-750,3450)","0","standard","I102";
;
CDS_LIB"standard"
BODY_TYPE"PLUMBING"
HDL_TAP"TRUE";
"B \NAC \NWC"13;
"S \NAC"
BN"10"78;
%"TAP"
"1","(-950,3700)","0","standard","I103";
;
CDS_LIB"standard"
BODY_TYPE"PLUMBING"
HDL_TAP"TRUE";
"B \NAC \NWC"14;
"S \NAC"
BN"11"76;
%"TAP"
"1","(-950,3900)","0","standard","I104";
;
CDS_LIB"standard"
BODY_TYPE"PLUMBING"
HDL_TAP"TRUE";
"B \NAC \NWC"14;
"S \NAC"
BN"12"74;
%"TAP"
"1","(-750,3650)","0","standard","I105";
;
CDS_LIB"standard"
BODY_TYPE"PLUMBING"
HDL_TAP"TRUE";
"B \NAC \NWC"13;
"S \NAC"
BN"11"75;
%"TAP"
"1","(-750,3850)","0","standard","I106";
;
CDS_LIB"standard"
BODY_TYPE"PLUMBING"
HDL_TAP"TRUE";
"B \NAC \NWC"13;
"S \NAC"
BN"12"73;
%"Q_CAP_DIFFBUS"
"2","(-1500,4050)","2","pure_quanta","I107";
;
LOCATION"C53"
$SEC"1"
CDS_SEC"1"
VALUE"DIFF BUS_0.22UF"
PIN_NAMES_ROTATE"TRUE"
VOLTAGE"6.3V"
MATERIAL"X6S"
PACK_TYPE"C0201"
TOLERANCE"20%"
CDS_LMAN_SYM_OUTLINE"-25,50,25,-50"
CDS_LIB"pure_quanta"
PART_NUMBER"SP_CH4221MEE01";
"2"
$PN"2"98;
"1"
$PN"1"104;
%"Q_CAP_DIFFBUS"
"2","(-1375,-150)","2","pure_quanta","I11";
;
LOCATION"C1994"
$SEC"1"
CDS_SEC"1"
VALUE"DIFF BUS_0.22UF"
CDS_LIB"pure_quanta"
CDS_LMAN_SYM_OUTLINE"-25,50,25,-50"
PIN_NAMES_ROTATE"TRUE"
VOLTAGE"6.3V"
MATERIAL"X6S"
PACK_TYPE"C0201"
TOLERANCE"20%"
PART_NUMBER"SP_CH4221MEE01";
"2"
$PN"2"27;
"1"
$PN"1"35;
%"TAP"
"1","(-2475,4250)","2","standard","I110";
;
CDS_LIB"standard"
BODY_TYPE"PLUMBING"
HDL_TAP"TRUE";
"B \NAC \NWC"15;
"S \NAC"
BN"14"97;
%"TAP"
"1","(-2475,4050)","2","standard","I111";
;
CDS_LIB"standard"
BODY_TYPE"PLUMBING"
HDL_TAP"TRUE";
"B \NAC \NWC"15;
"S \NAC"
BN"13"98;
%"TAP"
"1","(-2475,4450)","2","standard","I112";
;
CDS_LIB"standard"
BODY_TYPE"PLUMBING"
HDL_TAP"TRUE";
"B \NAC \NWC"15;
"S \NAC"
BN"15"96;
%"TAP"
"1","(-2225,4100)","2","standard","I113";
;
CDS_LIB"standard"
BODY_TYPE"PLUMBING"
HDL_TAP"TRUE";
"B \NAC \NWC"16;
"S \NAC"
BN"13"95;
%"TAP"
"1","(-2225,4500)","2","standard","I114";
;
CDS_LIB"standard"
BODY_TYPE"PLUMBING"
HDL_TAP"TRUE";
"B \NAC \NWC"16;
"S \NAC"
BN"15"94;
%"TAP"
"1","(-2225,4300)","2","standard","I115";
;
CDS_LIB"standard"
BODY_TYPE"PLUMBING"
HDL_TAP"TRUE";
"B \NAC \NWC"16;
"S \NAC"
BN"14"93;
%"Q_CAP_DIFFBUS"
"2","(-1500,4100)","2","pure_quanta","I116";
;
LOCATION"C52"
$SEC"1"
CDS_SEC"1"
VALUE"DIFF BUS_0.22UF"
PIN_NAMES_ROTATE"TRUE"
VOLTAGE"6.3V"
MATERIAL"X6S"
PACK_TYPE"C0201"
TOLERANCE"20%"
CDS_LMAN_SYM_OUTLINE"-25,50,25,-50"
CDS_LIB"pure_quanta"
PART_NUMBER"SP_CH4221MEE01";
"2"
$PN"2"95;
"1"
$PN"1"102;
%"Q_CAP_DIFFBUS"
"2","(-1500,4250)","2","pure_quanta","I117";
;
LOCATION"C51"
$SEC"1"
CDS_SEC"1"
VALUE"DIFF BUS_0.22UF"
PIN_NAMES_ROTATE"TRUE"
VOLTAGE"6.3V"
MATERIAL"X6S"
PACK_TYPE"C0201"
TOLERANCE"20%"
CDS_LMAN_SYM_OUTLINE"-25,50,25,-50"
CDS_LIB"pure_quanta"
PART_NUMBER"SP_CH4221MEE01";
"2"
$PN"2"97;
"1"
$PN"1"103;
%"Q_CAP_DIFFBUS"
"2","(-1500,4300)","2","pure_quanta","I118";
;
LOCATION"C50"
$SEC"1"
CDS_SEC"1"
VALUE"DIFF BUS_0.22UF"
PIN_NAMES_ROTATE"TRUE"
VOLTAGE"6.3V"
MATERIAL"X6S"
PACK_TYPE"C0201"
TOLERANCE"20%"
CDS_LMAN_SYM_OUTLINE"-25,50,25,-50"
CDS_LIB"pure_quanta"
PART_NUMBER"SP_CH4221MEE01";
"2"
$PN"2"93;
"1"
$PN"1"99;
%"Q_CAP_DIFFBUS"
"2","(-1500,4500)","2","pure_quanta","I119";
;
LOCATION"C48"
$SEC"1"
CDS_SEC"1"
VOLTAGE"6.3V"
TOLERANCE"20%"
MATERIAL"X6S"
PACK_TYPE"C0201"
VALUE"DIFF BUS_0.22UF"
PIN_NAMES_ROTATE"TRUE"
CDS_LIB"pure_quanta"
CDS_LMAN_SYM_OUTLINE"-25,50,25,-50"
PART_NUMBER"SP_CH4221MEE01";
"2"
$PN"2"94;
"1"
$PN"1"101;
%"Q_CAP_DIFFBUS"
"2","(-1375,-100)","2","pure_quanta","I12";
;
LOCATION"C1993"
$SEC"1"
CDS_SEC"1"
VALUE"DIFF BUS_0.22UF"
CDS_LIB"pure_quanta"
CDS_LMAN_SYM_OUTLINE"-25,50,25,-50"
PIN_NAMES_ROTATE"TRUE"
VOLTAGE"6.3V"
MATERIAL"X6S"
PACK_TYPE"C0201"
TOLERANCE"20%"
PART_NUMBER"SP_CH4221MEE01";
"2"
$PN"2"29;
"1"
$PN"1"36;
%"Q_CAP_DIFFBUS"
"2","(-1500,4450)","2","pure_quanta","I120";
;
LOCATION"C49"
$SEC"1"
CDS_SEC"1"
VALUE"DIFF BUS_0.22UF"
PIN_NAMES_ROTATE"TRUE"
VOLTAGE"6.3V"
MATERIAL"X6S"
PACK_TYPE"C0201"
TOLERANCE"20%"
CDS_LMAN_SYM_OUTLINE"-25,50,25,-50"
CDS_LIB"pure_quanta"
PART_NUMBER"SP_CH4221MEE01";
"2"
$PN"2"96;
"1"
$PN"1"100;
%"TAP"
"1","(-950,4100)","0","standard","I121";
;
CDS_LIB"standard"
BODY_TYPE"PLUMBING"
HDL_TAP"TRUE";
"B \NAC \NWC"14;
"S \NAC"
BN"13"102;
%"TAP"
"1","(-950,4500)","0","standard","I122";
;
CDS_LIB"standard"
BODY_TYPE"PLUMBING"
HDL_TAP"TRUE";
"B \NAC \NWC"14;
"S \NAC"
BN"15"101;
%"TAP"
"1","(-950,4300)","0","standard","I123";
;
CDS_LIB"standard"
BODY_TYPE"PLUMBING"
HDL_TAP"TRUE";
"B \NAC \NWC"14;
"S \NAC"
BN"14"99;
%"TAP"
"1","(-750,4050)","0","standard","I124";
;
CDS_LIB"standard"
BODY_TYPE"PLUMBING"
HDL_TAP"TRUE";
"B \NAC \NWC"13;
"S \NAC"
BN"13"104;
%"TAP"
"1","(-750,4250)","0","standard","I125";
;
CDS_LIB"standard"
BODY_TYPE"PLUMBING"
HDL_TAP"TRUE";
"B \NAC \NWC"13;
"S \NAC"
BN"14"103;
%"TAP"
"1","(-750,4450)","0","standard","I126";
;
CDS_LIB"standard"
BODY_TYPE"PLUMBING"
HDL_TAP"TRUE";
"B \NAC \NWC"13;
"S \NAC"
BN"15"100;
%"TAP"
"1","(2175,-625)","2","standard","I127";
;
CDS_LIB"standard"
BODY_TYPE"PLUMBING"
HDL_TAP"TRUE";
"B \NAC \NWC"12;
"S \NAC"
BN"3"110;
%"TAP"
"1","(2175,-425)","2","standard","I128";
;
CDS_LIB"standard"
BODY_TYPE"PLUMBING"
HDL_TAP"TRUE";
"B \NAC \NWC"12;
"S \NAC"
BN"2"107;
%"TAP"
"1","(2175,-225)","2","standard","I129";
;
CDS_LIB"standard"
BODY_TYPE"PLUMBING"
HDL_TAP"TRUE";
"B \NAC \NWC"12;
"S \NAC"
BN"1"106;
%"TAP"
"1","(-825,-500)","0","standard","I13";
;
CDS_LIB"standard"
BODY_TYPE"PLUMBING"
HDL_TAP"TRUE";
"B \NAC \NWC"19;
"S \NAC"
BN"3"32;
%"TAP"
"1","(2425,-575)","2","standard","I130";
;
CDS_LIB"standard"
BODY_TYPE"PLUMBING"
HDL_TAP"TRUE";
"B \NAC \NWC"11;
"S \NAC"
BN"3"109;
%"TAP"
"1","(2425,-375)","2","standard","I131";
;
CDS_LIB"standard"
BODY_TYPE"PLUMBING"
HDL_TAP"TRUE";
"B \NAC \NWC"11;
"S \NAC"
BN"2"108;
%"TAP"
"1","(2425,-175)","2","standard","I132";
;
CDS_LIB"standard"
BODY_TYPE"PLUMBING"
HDL_TAP"TRUE";
"B \NAC \NWC"11;
"S \NAC"
BN"1"105;
%"Q_CAP_DIFFBUS"
"2","(3150,-625)","2","pure_quanta","I133";
;
LOCATION"C1099"
$SEC"1"
CDS_SEC"1"
VALUE"DIFF BUS_0.22UF"
PIN_NAMES_ROTATE"TRUE"
VOLTAGE"6.3V"
MATERIAL"X6S"
PACK_TYPE"C0201"
TOLERANCE"20%"
CDS_LMAN_SYM_OUTLINE"-25,50,25,-50"
CDS_LIB"pure_quanta"
PART_NUMBER"SP_CH4221MEE01";
"2"
$PN"2"110;
"1"
$PN"1"115;
%"Q_CAP_DIFFBUS"
"2","(3150,-575)","2","pure_quanta","I134";
;
LOCATION"C1098"
$SEC"1"
CDS_SEC"1"
VALUE"DIFF BUS_0.22UF"
TOLERANCE"20%"
PACK_TYPE"C0201"
MATERIAL"X6S"
VOLTAGE"6.3V"
PIN_NAMES_ROTATE"TRUE"
CDS_LMAN_SYM_OUTLINE"-25,50,25,-50"
CDS_LIB"pure_quanta"
PART_NUMBER"SP_CH4221MEE01";
"2"
$PN"2"109;
"1"
$PN"1"116;
%"Q_CAP_DIFFBUS"
"2","(3150,-425)","2","pure_quanta","I135";
;
LOCATION"C1101"
$SEC"1"
CDS_SEC"1"
VALUE"DIFF BUS_0.22UF"
TOLERANCE"20%"
PACK_TYPE"C0201"
MATERIAL"X6S"
VOLTAGE"6.3V"
PIN_NAMES_ROTATE"TRUE"
CDS_LMAN_SYM_OUTLINE"-25,50,25,-50"
CDS_LIB"pure_quanta"
PART_NUMBER"SP_CH4221MEE01";
"2"
$PN"2"107;
"1"
$PN"1"113;
%"Q_CAP_DIFFBUS"
"2","(3150,-375)","2","pure_quanta","I136";
;
LOCATION"C1100"
$SEC"1"
CDS_SEC"1"
VALUE"DIFF BUS_0.22UF"
TOLERANCE"20%"
PACK_TYPE"C0201"
MATERIAL"X6S"
VOLTAGE"6.3V"
PIN_NAMES_ROTATE"TRUE"
CDS_LMAN_SYM_OUTLINE"-25,50,25,-50"
CDS_LIB"pure_quanta"
PART_NUMBER"SP_CH4221MEE01";
"2"
$PN"2"108;
"1"
$PN"1"112;
%"Q_CAP_DIFFBUS"
"2","(3150,-225)","2","pure_quanta","I137";
;
LOCATION"C9103"
$SEC"1"
CDS_SEC"1"
VALUE"DIFF BUS_0.22UF"
TOLERANCE"20%"
PACK_TYPE"C0201"
MATERIAL"X6S"
VOLTAGE"6.3V"
PIN_NAMES_ROTATE"TRUE"
CDS_LMAN_SYM_OUTLINE"-25,50,25,-50"
CDS_LIB"pure_quanta"
PART_NUMBER"SP_CH4221MEE01";
"2"
$PN"2"106;
"1"
$PN"1"111;
%"Q_CAP_DIFFBUS"
"2","(3150,-175)","2","pure_quanta","I138";
;
LOCATION"C9102"
$SEC"1"
CDS_SEC"1"
VALUE"DIFF BUS_0.22UF"
TOLERANCE"20%"
PACK_TYPE"C0201"
MATERIAL"X6S"
VOLTAGE"6.3V"
PIN_NAMES_ROTATE"TRUE"
CDS_LMAN_SYM_OUTLINE"-25,50,25,-50"
CDS_LIB"pure_quanta"
PART_NUMBER"SP_CH4221MEE01";
"2"
$PN"2"105;
"1"
$PN"1"114;
%"TAP"
"1","(3900,-625)","0","standard","I139";
;
CDS_LIB"standard"
BODY_TYPE"PLUMBING"
HDL_TAP"TRUE";
"B \NAC \NWC"10;
"S \NAC"
BN"3"115;
%"TAP"
"1","(-825,-300)","0","standard","I14";
;
CDS_LIB"standard"
BODY_TYPE"PLUMBING"
HDL_TAP"TRUE";
"B \NAC \NWC"19;
"S \NAC"
BN"2"34;
%"TAP"
"1","(3700,-575)","0","standard","I140";
;
CDS_LIB"standard"
BODY_TYPE"PLUMBING"
HDL_TAP"TRUE";
"B \NAC \NWC"9;
"S \NAC"
BN"3"116;
%"TAP"
"1","(3700,-375)","0","standard","I141";
;
CDS_LIB"standard"
BODY_TYPE"PLUMBING"
HDL_TAP"TRUE";
"B \NAC \NWC"9;
"S \NAC"
BN"2"112;
%"TAP"
"1","(3700,-175)","0","standard","I142";
;
CDS_LIB"standard"
BODY_TYPE"PLUMBING"
HDL_TAP"TRUE";
"B \NAC \NWC"9;
"S \NAC"
BN"1"114;
%"TAP"
"1","(3900,-425)","0","standard","I143";
;
CDS_LIB"standard"
BODY_TYPE"PLUMBING"
HDL_TAP"TRUE";
"B \NAC \NWC"10;
"S \NAC"
BN"2"113;
%"TAP"
"1","(3900,-225)","0","standard","I144";
;
CDS_LIB"standard"
BODY_TYPE"PLUMBING"
HDL_TAP"TRUE";
"B \NAC \NWC"10;
"S \NAC"
BN"1"111;
%"TAP"
"1","(-825,-100)","0","standard","I15";
;
CDS_LIB"standard"
BODY_TYPE"PLUMBING"
HDL_TAP"TRUE";
"B \NAC \NWC"19;
"S \NAC"
BN"1"36;
%"TAP"
"1","(2175,-25)","2","standard","I153";
;
CDS_LIB"standard"
BODY_TYPE"PLUMBING"
HDL_TAP"TRUE";
"B \NAC \NWC"12;
"S \NAC"
BN"0"117;
%"TAP"
"1","(2425,25)","2","standard","I154";
;
CDS_LIB"standard"
BODY_TYPE"PLUMBING"
HDL_TAP"TRUE";
"B \NAC \NWC"11;
"S \NAC"
BN"0"118;
%"TAP"
"1","(2150,1450)","2","standard","I155";
;
CDS_LIB"standard"
BODY_TYPE"PLUMBING"
HDL_TAP"TRUE";
"B \NAC \NWC"1;
"S \NAC"
BN"0"124;
%"TAP"
"1","(2150,1650)","2","standard","I156";
;
CDS_LIB"standard"
BODY_TYPE"PLUMBING"
HDL_TAP"TRUE";
"B \NAC \NWC"1;
"S \NAC"
BN"1"119;
%"TAP"
"1","(2150,1850)","2","standard","I157";
;
CDS_LIB"standard"
BODY_TYPE"PLUMBING"
HDL_TAP"TRUE";
"B \NAC \NWC"1;
"S \NAC"
BN"2"122;
%"TAP"
"1","(2400,1500)","2","standard","I158";
;
CDS_LIB"standard"
BODY_TYPE"PLUMBING"
HDL_TAP"TRUE";
"B \NAC \NWC"8;
"S \NAC"
BN"0"120;
%"TAP"
"1","(2400,1700)","2","standard","I159";
;
CDS_LIB"standard"
BODY_TYPE"PLUMBING"
HDL_TAP"TRUE";
"B \NAC \NWC"8;
"S \NAC"
BN"1"121;
%"TAP"
"1","(-625,-550)","0","standard","I16";
;
CDS_LIB"standard"
BODY_TYPE"PLUMBING"
HDL_TAP"TRUE";
"B \NAC \NWC"20;
"S \NAC"
BN"3"31;
%"TAP"
"1","(2400,1900)","2","standard","I160";
;
CDS_LIB"standard"
BODY_TYPE"PLUMBING"
HDL_TAP"TRUE";
"B \NAC \NWC"8;
"S \NAC"
BN"2"123;
%"Q_CAP_DIFFBUS"
"2","(3150,-25)","2","pure_quanta","I161";
;
LOCATION"C9105"
$SEC"1"
CDS_SEC"1"
VALUE"DIFF BUS_0.22UF"
TOLERANCE"20%"
PACK_TYPE"C0201"
MATERIAL"X6S"
VOLTAGE"6.3V"
PIN_NAMES_ROTATE"TRUE"
CDS_LMAN_SYM_OUTLINE"-25,50,25,-50"
CDS_LIB"pure_quanta"
PART_NUMBER"SP_CH4221MEE01";
"2"
$PN"2"117;
"1"
$PN"1"125;
%"Q_CAP_DIFFBUS"
"2","(3150,25)","2","pure_quanta","I162";
;
LOCATION"C9104"
$SEC"1"
CDS_SEC"1"
VALUE"DIFF BUS_0.22UF"
VOLTAGE"6.3V"
MATERIAL"X6S"
TOLERANCE"20%"
PACK_TYPE"C0201"
PIN_NAMES_ROTATE"TRUE"
CDS_LMAN_SYM_OUTLINE"-25,50,25,-50"
CDS_LIB"pure_quanta"
PART_NUMBER"SP_CH4221MEE01";
"2"
$PN"2"118;
"1"
$PN"1"126;
%"TAP"
"1","(3700,25)","0","standard","I163";
;
CDS_LIB"standard"
BODY_TYPE"PLUMBING"
HDL_TAP"TRUE";
"B \NAC \NWC"9;
"S \NAC"
BN"0"126;
%"TAP"
"1","(3900,-25)","0","standard","I164";
;
CDS_LIB"standard"
BODY_TYPE"PLUMBING"
HDL_TAP"TRUE";
"B \NAC \NWC"10;
"S \NAC"
BN"0"125;
%"Q_CAP_DIFFBUS"
"2","(3125,1450)","2","pure_quanta","I165";
;
LOCATION"C709"
$SEC"1"
CDS_SEC"1"
VALUE"DIFF BUS_0.22UF"
TOLERANCE"20%"
PACK_TYPE"C0201"
MATERIAL"X6S"
VOLTAGE"6.3V"
CDS_LMAN_SYM_OUTLINE"-25,50,25,-50"
CDS_LIB"pure_quanta"
PIN_NAMES_ROTATE"TRUE"
PART_NUMBER"SP_CH4221MEE01"
LOCATION"C709";
"2"
$PN"2"124;
"1"
$PN"1"132;
%"Q_CAP_DIFFBUS"
"2","(3125,1500)","2","pure_quanta","I166";
;
LOCATION"C708"
$SEC"1"
CDS_SEC"1"
VALUE"DIFF BUS_0.22UF"
TOLERANCE"20%"
PACK_TYPE"C0201"
MATERIAL"X6S"
VOLTAGE"6.3V"
CDS_LMAN_SYM_OUTLINE"-25,50,25,-50"
CDS_LIB"pure_quanta"
PIN_NAMES_ROTATE"TRUE"
PART_NUMBER"SP_CH4221MEE01"
LOCATION"C708";
"2"
$PN"2"120;
"1"
$PN"1"127;
%"Q_CAP_DIFFBUS"
"2","(3125,1700)","2","pure_quanta","I167";
;
LOCATION"C706"
$SEC"1"
CDS_SEC"1"
VALUE"DIFF BUS_0.22UF"
TOLERANCE"20%"
PACK_TYPE"C0201"
MATERIAL"X6S"
VOLTAGE"6.3V"
CDS_LIB"pure_quanta"
CDS_LMAN_SYM_OUTLINE"-25,50,25,-50"
PIN_NAMES_ROTATE"TRUE"
PART_NUMBER"SP_CH4221MEE01"
LOCATION"C706";
"2"
$PN"2"121;
"1"
$PN"1"129;
%"Q_CAP_DIFFBUS"
"2","(3125,1650)","2","pure_quanta","I168";
;
LOCATION"C707"
$SEC"1"
CDS_SEC"1"
VALUE"DIFF BUS_0.22UF"
TOLERANCE"20%"
PACK_TYPE"C0201"
MATERIAL"X6S"
VOLTAGE"6.3V"
CDS_LMAN_SYM_OUTLINE"-25,50,25,-50"
CDS_LIB"pure_quanta"
PIN_NAMES_ROTATE"TRUE"
PART_NUMBER"SP_CH4221MEE01"
LOCATION"C707";
"2"
$PN"2"119;
"1"
$PN"1"128;
%"Q_CAP_DIFFBUS"
"2","(3125,1850)","2","pure_quanta","I169";
;
LOCATION"C705"
$SEC"1"
CDS_SEC"1"
VALUE"DIFF BUS_0.22UF"
TOLERANCE"20%"
PACK_TYPE"C0201"
MATERIAL"X6S"
VOLTAGE"6.3V"
CDS_LMAN_SYM_OUTLINE"-25,50,25,-50"
CDS_LIB"pure_quanta"
PIN_NAMES_ROTATE"TRUE"
PART_NUMBER"SP_CH4221MEE01"
LOCATION"C705";
"2"
$PN"2"122;
"1"
$PN"1"130;
%"TAP"
"1","(-625,-350)","0","standard","I17";
;
CDS_LIB"standard"
BODY_TYPE"PLUMBING"
HDL_TAP"TRUE";
"B \NAC \NWC"20;
"S \NAC"
BN"2"33;
%"Q_CAP_DIFFBUS"
"2","(3125,1900)","2","pure_quanta","I170";
;
LOCATION"C704"
$SEC"1"
CDS_SEC"1"
VALUE"DIFF BUS_0.22UF"
TOLERANCE"20%"
PACK_TYPE"C0201"
MATERIAL"X6S"
VOLTAGE"6.3V"
CDS_LMAN_SYM_OUTLINE"-25,50,25,-50"
CDS_LIB"pure_quanta"
PIN_NAMES_ROTATE"TRUE"
PART_NUMBER"SP_CH4221MEE01"
LOCATION"C704";
"2"
$PN"2"123;
"1"
$PN"1"131;
%"TAP"
"1","(3875,1450)","0","standard","I171";
;
CDS_LIB"standard"
BODY_TYPE"PLUMBING"
HDL_TAP"TRUE";
"B \NAC \NWC"4;
"S \NAC"
BN"0"132;
%"TAP"
"1","(3675,1500)","0","standard","I172";
;
CDS_LIB"standard"
BODY_TYPE"PLUMBING"
HDL_TAP"TRUE";
"B \NAC \NWC"7;
"S \NAC"
BN"0"127;
%"TAP"
"1","(3675,1700)","0","standard","I173";
;
CDS_LIB"standard"
BODY_TYPE"PLUMBING"
HDL_TAP"TRUE";
"B \NAC \NWC"7;
"S \NAC"
BN"1"129;
%"TAP"
"1","(3675,1900)","0","standard","I174";
;
CDS_LIB"standard"
BODY_TYPE"PLUMBING"
HDL_TAP"TRUE";
"B \NAC \NWC"7;
"S \NAC"
BN"2"131;
%"TAP"
"1","(3875,1650)","0","standard","I175";
;
CDS_LIB"standard"
BODY_TYPE"PLUMBING"
HDL_TAP"TRUE";
"B \NAC \NWC"4;
"S \NAC"
BN"1"128;
%"TAP"
"1","(3875,1850)","0","standard","I176";
;
CDS_LIB"standard"
BODY_TYPE"PLUMBING"
HDL_TAP"TRUE";
"B \NAC \NWC"4;
"S \NAC"
BN"2"130;
%"TAP"
"1","(2150,2050)","2","standard","I177";
;
CDS_LIB"standard"
BODY_TYPE"PLUMBING"
HDL_TAP"TRUE";
"B \NAC \NWC"1;
"S \NAC"
BN"3"135;
%"TAP"
"1","(2150,2450)","2","standard","I178";
;
CDS_LIB"standard"
BODY_TYPE"PLUMBING"
HDL_TAP"TRUE";
"B \NAC \NWC"1;
"S \NAC"
BN"5"139;
%"TAP"
"1","(2150,2250)","2","standard","I179";
;
CDS_LIB"standard"
BODY_TYPE"PLUMBING"
HDL_TAP"TRUE";
"B \NAC \NWC"1;
"S \NAC"
BN"4"136;
%"TAP"
"1","(-625,-150)","0","standard","I18";
;
CDS_LIB"standard"
BODY_TYPE"PLUMBING"
HDL_TAP"TRUE";
"B \NAC \NWC"20;
"S \NAC"
BN"1"35;
%"TAP"
"1","(2400,2100)","2","standard","I180";
;
CDS_LIB"standard"
BODY_TYPE"PLUMBING"
HDL_TAP"TRUE";
"B \NAC \NWC"8;
"S \NAC"
BN"3"138;
%"TAP"
"1","(2400,2300)","2","standard","I181";
;
CDS_LIB"standard"
BODY_TYPE"PLUMBING"
HDL_TAP"TRUE";
"B \NAC \NWC"8;
"S \NAC"
BN"4"137;
%"TAP"
"1","(2150,2650)","2","standard","I182";
;
CDS_LIB"standard"
BODY_TYPE"PLUMBING"
HDL_TAP"TRUE";
"B \NAC \NWC"1;
"S \NAC"
BN"6"184;
%"TAP"
"1","(2150,2850)","2","standard","I183";
;
CDS_LIB"standard"
BODY_TYPE"PLUMBING"
HDL_TAP"TRUE";
"B \NAC \NWC"1;
"S \NAC"
BN"7"140;
%"TAP"
"1","(2400,2700)","2","standard","I184";
;
CDS_LIB"standard"
BODY_TYPE"PLUMBING"
HDL_TAP"TRUE";
"B \NAC \NWC"8;
"S \NAC"
BN"6"134;
%"TAP"
"1","(2400,2500)","2","standard","I185";
;
CDS_LIB"standard"
BODY_TYPE"PLUMBING"
HDL_TAP"TRUE";
"B \NAC \NWC"8;
"S \NAC"
BN"5"141;
%"TAP"
"1","(2400,2900)","2","standard","I186";
;
CDS_LIB"standard"
BODY_TYPE"PLUMBING"
HDL_TAP"TRUE";
"B \NAC \NWC"8;
"S \NAC"
BN"7"142;
%"TAP"
"1","(2150,3050)","2","standard","I187";
;
CDS_LIB"standard"
BODY_TYPE"PLUMBING"
HDL_TAP"TRUE";
"B \NAC \NWC"6;
"S \NAC"
BN"8"144;
%"TAP"
"1","(2150,3250)","2","standard","I188";
;
CDS_LIB"standard"
BODY_TYPE"PLUMBING"
HDL_TAP"TRUE";
"B \NAC \NWC"6;
"S \NAC"
BN"9"143;
%"TAP"
"1","(2150,3450)","2","standard","I189";
;
CDS_LIB"standard"
BODY_TYPE"PLUMBING"
HDL_TAP"TRUE";
"B \NAC \NWC"6;
"S \NAC"
BN"10"133;
%"TAP"
"1","(2400,3100)","2","standard","I190";
;
CDS_LIB"standard"
BODY_TYPE"PLUMBING"
HDL_TAP"TRUE";
"B \NAC \NWC"5;
"S \NAC"
BN"8"145;
%"TAP"
"1","(2400,3300)","2","standard","I191";
;
CDS_LIB"standard"
BODY_TYPE"PLUMBING"
HDL_TAP"TRUE";
"B \NAC \NWC"5;
"S \NAC"
BN"9"146;
%"TAP"
"1","(2400,3500)","2","standard","I192";
;
CDS_LIB"standard"
BODY_TYPE"PLUMBING"
HDL_TAP"TRUE";
"B \NAC \NWC"5;
"S \NAC"
BN"10"147;
%"TAP"
"1","(2150,3650)","2","standard","I193";
;
CDS_LIB"standard"
BODY_TYPE"PLUMBING"
HDL_TAP"TRUE";
"B \NAC \NWC"6;
"S \NAC"
BN"11"148;
%"TAP"
"1","(2150,3850)","2","standard","I194";
;
CDS_LIB"standard"
BODY_TYPE"PLUMBING"
HDL_TAP"TRUE";
"B \NAC \NWC"6;
"S \NAC"
BN"12"149;
%"TAP"
"1","(2400,3700)","2","standard","I195";
;
CDS_LIB"standard"
BODY_TYPE"PLUMBING"
HDL_TAP"TRUE";
"B \NAC \NWC"5;
"S \NAC"
BN"11"150;
%"TAP"
"1","(2400,3900)","2","standard","I196";
;
CDS_LIB"standard"
BODY_TYPE"PLUMBING"
HDL_TAP"TRUE";
"B \NAC \NWC"5;
"S \NAC"
BN"12"151;
%"Q_CAP_DIFFBUS"
"2","(3125,2100)","2","pure_quanta","I197";
;
LOCATION"C702"
$SEC"1"
CDS_SEC"1"
VALUE"DIFF BUS_0.22UF"
TOLERANCE"20%"
PACK_TYPE"C0201"
MATERIAL"X6S"
VOLTAGE"6.3V"
CDS_LIB"pure_quanta"
CDS_LMAN_SYM_OUTLINE"-25,50,25,-50"
PIN_NAMES_ROTATE"TRUE"
PART_NUMBER"SP_CH4221MEE01"
LOCATION"C702";
"2"
$PN"2"138;
"1"
$PN"1"153;
%"Q_CAP_DIFFBUS"
"2","(3125,2050)","2","pure_quanta","I198";
;
LOCATION"C703"
$SEC"1"
CDS_SEC"1"
VALUE"DIFF BUS_0.22UF"
TOLERANCE"20%"
PACK_TYPE"C0201"
MATERIAL"X6S"
VOLTAGE"6.3V"
CDS_LIB"pure_quanta"
CDS_LMAN_SYM_OUTLINE"-25,50,25,-50"
PIN_NAMES_ROTATE"TRUE"
PART_NUMBER"SP_CH4221MEE01"
LOCATION"C703";
"2"
$PN"2"135;
"1"
$PN"1"152;
%"Q_CAP_DIFFBUS"
"2","(3125,2250)","2","pure_quanta","I199";
;
LOCATION"C701"
$SEC"1"
CDS_SEC"1"
VALUE"DIFF BUS_0.22UF"
TOLERANCE"20%"
PACK_TYPE"C0201"
MATERIAL"X6S"
VOLTAGE"6.3V"
CDS_LMAN_SYM_OUTLINE"-25,50,25,-50"
CDS_LIB"pure_quanta"
PIN_NAMES_ROTATE"TRUE"
PART_NUMBER"SP_CH4221MEE01"
LOCATION"C701";
"2"
$PN"2"136;
"1"
$PN"1"154;
%"TAP"
"1","(-2350,-150)","2","standard","I2";
;
CDS_LIB"standard"
BODY_TYPE"PLUMBING"
HDL_TAP"TRUE";
"B \NAC \NWC"24;
"S \NAC"
BN"1"27;
%"Q_CAP_DIFFBUS"
"2","(3125,2300)","2","pure_quanta","I200";
;
LOCATION"C700"
$SEC"1"
CDS_SEC"1"
VALUE"DIFF BUS_0.22UF"
TOLERANCE"20%"
PACK_TYPE"C0201"
MATERIAL"X6S"
VOLTAGE"6.3V"
CDS_LMAN_SYM_OUTLINE"-25,50,25,-50"
CDS_LIB"pure_quanta"
PIN_NAMES_ROTATE"TRUE"
PART_NUMBER"SP_CH4221MEE01"
LOCATION"C700";
"2"
$PN"2"137;
"1"
$PN"1"155;
%"Q_CAP_DIFFBUS"
"2","(3125,2500)","2","pure_quanta","I201";
;
LOCATION"C698"
$SEC"1"
CDS_SEC"1"
VALUE"DIFF BUS_0.22UF"
TOLERANCE"20%"
PACK_TYPE"C0201"
MATERIAL"X6S"
VOLTAGE"6.3V"
CDS_LMAN_SYM_OUTLINE"-25,50,25,-50"
CDS_LIB"pure_quanta"
PIN_NAMES_ROTATE"TRUE"
PART_NUMBER"SP_CH4221MEE01"
LOCATION"C698";
"2"
$PN"2"141;
"1"
$PN"1"157;
%"Q_CAP_DIFFBUS"
"2","(3125,2450)","2","pure_quanta","I202";
;
LOCATION"C699"
$SEC"1"
CDS_SEC"1"
VALUE"DIFF BUS_0.22UF"
TOLERANCE"20%"
PACK_TYPE"C0201"
MATERIAL"X6S"
VOLTAGE"6.3V"
CDS_LMAN_SYM_OUTLINE"-25,50,25,-50"
CDS_LIB"pure_quanta"
PIN_NAMES_ROTATE"TRUE"
PART_NUMBER"SP_CH4221MEE01"
LOCATION"C699";
"2"
$PN"2"139;
"1"
$PN"1"156;
%"Q_CAP_DIFFBUS"
"2","(3125,2650)","2","pure_quanta","I203";
;
LOCATION"C697"
$SEC"1"
CDS_SEC"1"
VALUE"DIFF BUS_0.22UF"
TOLERANCE"20%"
PACK_TYPE"C0201"
MATERIAL"X6S"
VOLTAGE"6.3V"
CDS_LMAN_SYM_OUTLINE"-25,50,25,-50"
CDS_LIB"pure_quanta"
PIN_NAMES_ROTATE"TRUE"
PART_NUMBER"SP_CH4221MEE01"
LOCATION"C697";
"2"
$PN"2"184;
"1"
$PN"1"159;
%"Q_CAP_DIFFBUS"
"2","(3125,2700)","2","pure_quanta","I204";
;
LOCATION"C696"
$SEC"1"
CDS_SEC"1"
VALUE"DIFF BUS_0.22UF"
TOLERANCE"20%"
PACK_TYPE"C0201"
MATERIAL"X6S"
VOLTAGE"6.3V"
CDS_LMAN_SYM_OUTLINE"-25,50,25,-50"
CDS_LIB"pure_quanta"
PIN_NAMES_ROTATE"TRUE"
PART_NUMBER"SP_CH4221MEE01"
LOCATION"C696";
"2"
$PN"2"134;
"1"
$PN"1"158;
%"Q_CAP_DIFFBUS"
"2","(3125,2850)","2","pure_quanta","I205";
;
LOCATION"C695"
$SEC"1"
CDS_SEC"1"
VALUE"DIFF BUS_0.22UF"
TOLERANCE"20%"
PACK_TYPE"C0201"
MATERIAL"X6S"
VOLTAGE"6.3V"
CDS_LMAN_SYM_OUTLINE"-25,50,25,-50"
CDS_LIB"pure_quanta"
PIN_NAMES_ROTATE"TRUE"
PART_NUMBER"SP_CH4221MEE01"
LOCATION"C695";
"2"
$PN"2"140;
"1"
$PN"1"179;
%"Q_CAP_DIFFBUS"
"2","(3125,2900)","2","pure_quanta","I206";
;
LOCATION"C694"
$SEC"1"
CDS_SEC"1"
VALUE"DIFF BUS_0.22UF"
TOLERANCE"20%"
PACK_TYPE"C0201"
MATERIAL"X6S"
VOLTAGE"6.3V"
CDS_LIB"pure_quanta"
CDS_LMAN_SYM_OUTLINE"-25,50,25,-50"
PIN_NAMES_ROTATE"TRUE"
PART_NUMBER"SP_CH4221MEE01"
LOCATION"C694";
"2"
$PN"2"142;
"1"
$PN"1"160;
%"TAP"
"1","(3675,2100)","0","standard","I207";
;
CDS_LIB"standard"
BODY_TYPE"PLUMBING"
HDL_TAP"TRUE";
"B \NAC \NWC"7;
"S \NAC"
BN"3"153;
%"TAP"
"1","(3675,2300)","0","standard","I208";
;
CDS_LIB"standard"
BODY_TYPE"PLUMBING"
HDL_TAP"TRUE";
"B \NAC \NWC"7;
"S \NAC"
BN"4"155;
%"TAP"
"1","(3875,2250)","0","standard","I209";
;
CDS_LIB"standard"
BODY_TYPE"PLUMBING"
HDL_TAP"TRUE";
"B \NAC \NWC"4;
"S \NAC"
BN"4"154;
%"TAP"
"1","(-2350,50)","2","standard","I21";
;
CDS_LIB"standard"
BODY_TYPE"PLUMBING"
HDL_TAP"TRUE";
"B \NAC \NWC"24;
"S \NAC"
BN"0"37;
%"TAP"
"1","(3875,2450)","0","standard","I210";
;
CDS_LIB"standard"
BODY_TYPE"PLUMBING"
HDL_TAP"TRUE";
"B \NAC \NWC"4;
"S \NAC"
BN"5"156;
%"TAP"
"1","(3675,2700)","0","standard","I211";
;
CDS_LIB"standard"
BODY_TYPE"PLUMBING"
HDL_TAP"TRUE";
"B \NAC \NWC"7;
"S \NAC"
BN"6"158;
%"TAP"
"1","(3675,2500)","0","standard","I212";
;
CDS_LIB"standard"
BODY_TYPE"PLUMBING"
HDL_TAP"TRUE";
"B \NAC \NWC"7;
"S \NAC"
BN"5"157;
%"TAP"
"1","(3675,2900)","0","standard","I213";
;
CDS_LIB"standard"
BODY_TYPE"PLUMBING"
HDL_TAP"TRUE";
"B \NAC \NWC"7;
"S \NAC"
BN"7"160;
%"TAP"
"1","(3875,2650)","0","standard","I214";
;
CDS_LIB"standard"
BODY_TYPE"PLUMBING"
HDL_TAP"TRUE";
"B \NAC \NWC"4;
"S \NAC"
BN"6"159;
%"TAP"
"1","(3875,2850)","0","standard","I215";
;
CDS_LIB"standard"
BODY_TYPE"PLUMBING"
HDL_TAP"TRUE";
"B \NAC \NWC"4;
"S \NAC"
BN"7"179;
%"Q_CAP_DIFFBUS"
"2","(3125,3050)","2","pure_quanta","I216";
;
LOCATION"C56"
$SEC"1"
CDS_SEC"1"
VALUE"DIFF BUS_0.22UF"
CDS_LMAN_SYM_OUTLINE"-25,50,25,-50"
CDS_LIB"pure_quanta"
PIN_NAMES_ROTATE"TRUE"
VOLTAGE"6.3V"
MATERIAL"X6S"
PACK_TYPE"C0201"
TOLERANCE"20%"
PART_NUMBER"SP_CH4221MEE01";
"2"
$PN"2"144;
"1"
$PN"1"183;
%"Q_CAP_DIFFBUS"
"2","(3125,3100)","2","pure_quanta","I217";
;
LOCATION"C692"
$SEC"1"
CDS_SEC"1"
VALUE"DIFF BUS_0.22UF"
CDS_LMAN_SYM_OUTLINE"-25,50,25,-50"
CDS_LIB"pure_quanta"
PIN_NAMES_ROTATE"TRUE"
VOLTAGE"6.3V"
MATERIAL"X6S"
PACK_TYPE"C0201"
TOLERANCE"20%"
PART_NUMBER"SP_CH4221MEE01"
LOCATION"C692";
"2"
$PN"2"145;
"1"
$PN"1"180;
%"Q_CAP_DIFFBUS"
"2","(3125,3250)","2","pure_quanta","I218";
;
LOCATION"C691"
$SEC"1"
CDS_SEC"1"
VALUE"DIFF BUS_0.22UF"
CDS_LMAN_SYM_OUTLINE"-25,50,25,-50"
CDS_LIB"pure_quanta"
PIN_NAMES_ROTATE"TRUE"
VOLTAGE"6.3V"
MATERIAL"X6S"
PACK_TYPE"C0201"
TOLERANCE"20%"
PART_NUMBER"SP_CH4221MEE01"
LOCATION"C691";
"2"
$PN"2"143;
"1"
$PN"1"182;
%"Q_CAP_DIFFBUS"
"2","(3125,3300)","2","pure_quanta","I219";
;
LOCATION"C690"
$SEC"1"
CDS_SEC"1"
VALUE"DIFF BUS_0.22UF"
CDS_LIB"pure_quanta"
CDS_LMAN_SYM_OUTLINE"-25,50,25,-50"
PIN_NAMES_ROTATE"TRUE"
VOLTAGE"6.3V"
MATERIAL"X6S"
PACK_TYPE"C0201"
TOLERANCE"20%"
PART_NUMBER"SP_CH4221MEE01"
LOCATION"C690";
"2"
$PN"2"146;
"1"
$PN"1"181;
%"TAP"
"1","(-2100,100)","2","standard","I22";
;
CDS_LIB"standard"
BODY_TYPE"PLUMBING"
HDL_TAP"TRUE";
"B \NAC \NWC"21;
"S \NAC"
BN"0"64;
%"Q_CAP_DIFFBUS"
"2","(3125,3500)","2","pure_quanta","I220";
;
LOCATION"C688"
$SEC"1"
CDS_SEC"1"
VALUE"DIFF BUS_0.22UF"
CDS_LMAN_SYM_OUTLINE"-25,50,25,-50"
CDS_LIB"pure_quanta"
PIN_NAMES_ROTATE"TRUE"
VOLTAGE"6.3V"
MATERIAL"X6S"
PACK_TYPE"C0201"
TOLERANCE"20%"
PART_NUMBER"SP_CH4221MEE01"
LOCATION"C688";
"2"
$PN"2"147;
"1"
$PN"1"162;
%"Q_CAP_DIFFBUS"
"2","(3125,3450)","2","pure_quanta","I221";
;
LOCATION"C689"
$SEC"1"
CDS_SEC"1"
VALUE"DIFF BUS_0.22UF"
CDS_LMAN_SYM_OUTLINE"-25,50,25,-50"
CDS_LIB"pure_quanta"
PIN_NAMES_ROTATE"TRUE"
VOLTAGE"6.3V"
MATERIAL"X6S"
PACK_TYPE"C0201"
TOLERANCE"20%"
PART_NUMBER"SP_CH4221MEE01"
LOCATION"C689";
"2"
$PN"2"133;
"1"
$PN"1"161;
%"Q_CAP_DIFFBUS"
"2","(3125,3650)","2","pure_quanta","I222";
;
LOCATION"C687"
$SEC"1"
CDS_SEC"1"
VALUE"DIFF BUS_0.22UF"
CDS_LIB"pure_quanta"
CDS_LMAN_SYM_OUTLINE"-25,50,25,-50"
PIN_NAMES_ROTATE"TRUE"
VOLTAGE"6.3V"
MATERIAL"X6S"
PACK_TYPE"C0201"
TOLERANCE"20%"
PART_NUMBER"SP_CH4221MEE01"
LOCATION"C687";
"2"
$PN"2"148;
"1"
$PN"1"163;
%"Q_CAP_DIFFBUS"
"2","(3125,3700)","2","pure_quanta","I223";
;
LOCATION"C686"
$SEC"1"
CDS_SEC"1"
VALUE"DIFF BUS_0.22UF"
CDS_LIB"pure_quanta"
CDS_LMAN_SYM_OUTLINE"-25,50,25,-50"
PIN_NAMES_ROTATE"TRUE"
VOLTAGE"6.3V"
MATERIAL"X6S"
PACK_TYPE"C0201"
TOLERANCE"20%"
PART_NUMBER"SP_CH4221MEE01"
LOCATION"C686";
"2"
$PN"2"150;
"1"
$PN"1"164;
%"Q_CAP_DIFFBUS"
"2","(3125,3850)","2","pure_quanta","I224";
;
LOCATION"C685"
$SEC"1"
CDS_SEC"1"
VALUE"DIFF BUS_0.22UF"
CDS_LMAN_SYM_OUTLINE"-25,50,25,-50"
CDS_LIB"pure_quanta"
PIN_NAMES_ROTATE"TRUE"
VOLTAGE"6.3V"
MATERIAL"X6S"
PACK_TYPE"C0201"
TOLERANCE"20%"
PART_NUMBER"SP_CH4221MEE01"
LOCATION"C685";
"2"
$PN"2"149;
"1"
$PN"1"165;
%"Q_CAP_DIFFBUS"
"2","(3125,3900)","2","pure_quanta","I225";
;
LOCATION"C684"
$SEC"1"
CDS_SEC"1"
VALUE"DIFF BUS_0.22UF"
CDS_LMAN_SYM_OUTLINE"-25,50,25,-50"
CDS_LIB"pure_quanta"
PIN_NAMES_ROTATE"TRUE"
VOLTAGE"6.3V"
MATERIAL"X6S"
PACK_TYPE"C0201"
TOLERANCE"20%"
PART_NUMBER"SP_CH4221MEE01"
LOCATION"C684";
"2"
$PN"2"151;
"1"
$PN"1"166;
%"TAP"
"1","(3675,3100)","0","standard","I226";
;
CDS_LIB"standard"
BODY_TYPE"PLUMBING"
HDL_TAP"TRUE";
"B \NAC \NWC"3;
"S \NAC"
BN"8"180;
%"TAP"
"1","(3675,3300)","0","standard","I227";
;
CDS_LIB"standard"
BODY_TYPE"PLUMBING"
HDL_TAP"TRUE";
"B \NAC \NWC"3;
"S \NAC"
BN"9"181;
%"TAP"
"1","(3675,3500)","0","standard","I228";
;
CDS_LIB"standard"
BODY_TYPE"PLUMBING"
HDL_TAP"TRUE";
"B \NAC \NWC"3;
"S \NAC"
BN"10"162;
%"TAP"
"1","(3875,3250)","0","standard","I229";
;
CDS_LIB"standard"
BODY_TYPE"PLUMBING"
HDL_TAP"TRUE";
"B \NAC \NWC"2;
"S \NAC"
BN"9"182;
%"TAP"
"1","(-2500,1425)","2","standard","I23";
;
CDS_LIB"standard"
BODY_TYPE"PLUMBING"
HDL_TAP"TRUE";
"B \NAC \NWC"23;
"S \NAC"
BN"0"50;
%"TAP"
"1","(3875,3050)","0","standard","I230";
;
CDS_LIB"standard"
BODY_TYPE"PLUMBING"
HDL_TAP"TRUE";
"B \NAC \NWC"2;
"S \NAC"
BN"8"183;
%"TAP"
"1","(3875,3450)","0","standard","I231";
;
CDS_LIB"standard"
BODY_TYPE"PLUMBING"
HDL_TAP"TRUE";
"B \NAC \NWC"2;
"S \NAC"
BN"10"161;
%"TAP"
"1","(3675,3700)","0","standard","I232";
;
CDS_LIB"standard"
BODY_TYPE"PLUMBING"
HDL_TAP"TRUE";
"B \NAC \NWC"3;
"S \NAC"
BN"11"164;
%"TAP"
"1","(3675,3900)","0","standard","I233";
;
CDS_LIB"standard"
BODY_TYPE"PLUMBING"
HDL_TAP"TRUE";
"B \NAC \NWC"3;
"S \NAC"
BN"12"166;
%"TAP"
"1","(3875,3650)","0","standard","I234";
;
CDS_LIB"standard"
BODY_TYPE"PLUMBING"
HDL_TAP"TRUE";
"B \NAC \NWC"2;
"S \NAC"
BN"11"163;
%"TAP"
"1","(3875,3850)","0","standard","I235";
;
CDS_LIB"standard"
BODY_TYPE"PLUMBING"
HDL_TAP"TRUE";
"B \NAC \NWC"2;
"S \NAC"
BN"12"165;
%"Q_CAP_DIFFBUS"
"2","(3125,4050)","2","pure_quanta","I236";
;
LOCATION"C683"
$SEC"1"
CDS_SEC"1"
VALUE"DIFF BUS_0.22UF"
CDS_LMAN_SYM_OUTLINE"-25,50,25,-50"
CDS_LIB"pure_quanta"
PIN_NAMES_ROTATE"TRUE"
VOLTAGE"6.3V"
MATERIAL"X6S"
PACK_TYPE"C0201"
TOLERANCE"20%"
PART_NUMBER"SP_CH4221MEE01"
LOCATION"C683";
"2"
$PN"2"168;
"1"
$PN"1"173;
%"TAP"
"1","(-2500,1625)","2","standard","I24";
;
CDS_LIB"standard"
BODY_TYPE"PLUMBING"
HDL_TAP"TRUE";
"B \NAC \NWC"23;
"S \NAC"
BN"1"51;
%"TAP"
"1","(2150,4250)","2","standard","I241";
;
CDS_LIB"standard"
BODY_TYPE"PLUMBING"
HDL_TAP"TRUE";
"B \NAC \NWC"6;
"S \NAC"
BN"14"167;
%"TAP"
"1","(2150,4050)","2","standard","I242";
;
CDS_LIB"standard"
BODY_TYPE"PLUMBING"
HDL_TAP"TRUE";
"B \NAC \NWC"6;
"S \NAC"
BN"13"168;
%"TAP"
"1","(2150,4450)","2","standard","I243";
;
CDS_LIB"standard"
BODY_TYPE"PLUMBING"
HDL_TAP"TRUE";
"B \NAC \NWC"6;
"S \NAC"
BN"15"169;
%"TAP"
"1","(2400,4100)","2","standard","I244";
;
CDS_LIB"standard"
BODY_TYPE"PLUMBING"
HDL_TAP"TRUE";
"B \NAC \NWC"5;
"S \NAC"
BN"13"170;
%"TAP"
"1","(2400,4500)","2","standard","I245";
;
CDS_LIB"standard"
BODY_TYPE"PLUMBING"
HDL_TAP"TRUE";
"B \NAC \NWC"5;
"S \NAC"
BN"15"172;
%"TAP"
"1","(2400,4300)","2","standard","I246";
;
CDS_LIB"standard"
BODY_TYPE"PLUMBING"
HDL_TAP"TRUE";
"B \NAC \NWC"5;
"S \NAC"
BN"14"171;
%"Q_CAP_DIFFBUS"
"2","(3125,4100)","2","pure_quanta","I247";
;
LOCATION"C682"
$SEC"1"
CDS_SEC"1"
VALUE"DIFF BUS_0.22UF"
CDS_LMAN_SYM_OUTLINE"-25,50,25,-50"
CDS_LIB"pure_quanta"
PIN_NAMES_ROTATE"TRUE"
VOLTAGE"6.3V"
MATERIAL"X6S"
PACK_TYPE"C0201"
TOLERANCE"20%"
PART_NUMBER"SP_CH4221MEE01"
LOCATION"C682";
"2"
$PN"2"170;
"1"
$PN"1"174;
%"Q_CAP_DIFFBUS"
"2","(3125,4250)","2","pure_quanta","I248";
;
LOCATION"C681"
$SEC"1"
CDS_SEC"1"
VALUE"DIFF BUS_0.22UF"
CDS_LMAN_SYM_OUTLINE"-25,50,25,-50"
CDS_LIB"pure_quanta"
PIN_NAMES_ROTATE"TRUE"
VOLTAGE"6.3V"
MATERIAL"X6S"
PACK_TYPE"C0201"
TOLERANCE"20%"
PART_NUMBER"SP_CH4221MEE01"
LOCATION"C681";
"2"
$PN"2"167;
"1"
$PN"1"175;
%"Q_CAP_DIFFBUS"
"2","(3125,4300)","2","pure_quanta","I249";
;
LOCATION"C680"
$SEC"1"
CDS_SEC"1"
VALUE"DIFF BUS_0.22UF"
CDS_LMAN_SYM_OUTLINE"-25,50,25,-50"
CDS_LIB"pure_quanta"
PIN_NAMES_ROTATE"TRUE"
VOLTAGE"6.3V"
MATERIAL"X6S"
PACK_TYPE"C0201"
TOLERANCE"20%"
PART_NUMBER"SP_CH4221MEE01"
LOCATION"C680";
"2"
$PN"2"171;
"1"
$PN"1"176;
%"TAP"
"1","(-2500,1825)","2","standard","I25";
;
CDS_LIB"standard"
BODY_TYPE"PLUMBING"
HDL_TAP"TRUE";
"B \NAC \NWC"23;
"S \NAC"
BN"2"54;
%"Q_CAP_DIFFBUS"
"2","(3125,4450)","2","pure_quanta","I250";
;
LOCATION"C679"
$SEC"1"
CDS_SEC"1"
VALUE"DIFF BUS_0.22UF"
CDS_LMAN_SYM_OUTLINE"-25,50,25,-50"
CDS_LIB"pure_quanta"
PIN_NAMES_ROTATE"TRUE"
VOLTAGE"6.3V"
MATERIAL"X6S"
PACK_TYPE"C0201"
TOLERANCE"20%"
PART_NUMBER"SP_CH4221MEE01"
LOCATION"C679";
"2"
$PN"2"169;
"1"
$PN"1"177;
%"Q_CAP_DIFFBUS"
"2","(3125,4500)","2","pure_quanta","I251";
;
LOCATION"C678"
$SEC"1"
CDS_SEC"1"
VALUE"DIFF BUS_0.22UF"
MATERIAL"X6S"
PACK_TYPE"C0201"
VOLTAGE"6.3V"
TOLERANCE"20%"
CDS_LIB"pure_quanta"
CDS_LMAN_SYM_OUTLINE"-25,50,25,-50"
PIN_NAMES_ROTATE"TRUE"
PART_NUMBER"SP_CH4221MEE01"
LOCATION"C678";
"2"
$PN"2"172;
"1"
$PN"1"178;
%"TAP"
"1","(3675,4100)","0","standard","I252";
;
CDS_LIB"standard"
BODY_TYPE"PLUMBING"
HDL_TAP"TRUE";
"B \NAC \NWC"3;
"S \NAC"
BN"13"174;
%"TAP"
"1","(3675,4500)","0","standard","I253";
;
CDS_LIB"standard"
BODY_TYPE"PLUMBING"
HDL_TAP"TRUE";
"B \NAC \NWC"3;
"S \NAC"
BN"15"178;
%"TAP"
"1","(3675,4300)","0","standard","I254";
;
CDS_LIB"standard"
BODY_TYPE"PLUMBING"
HDL_TAP"TRUE";
"B \NAC \NWC"3;
"S \NAC"
BN"14"176;
%"TAP"
"1","(3875,4250)","0","standard","I255";
;
CDS_LIB"standard"
BODY_TYPE"PLUMBING"
HDL_TAP"TRUE";
"B \NAC \NWC"2;
"S \NAC"
BN"14"175;
%"TAP"
"1","(3875,4050)","0","standard","I256";
;
CDS_LIB"standard"
BODY_TYPE"PLUMBING"
HDL_TAP"TRUE";
"B \NAC \NWC"2;
"S \NAC"
BN"13"173;
%"TAP"
"1","(3875,4450)","0","standard","I257";
;
CDS_LIB"standard"
BODY_TYPE"PLUMBING"
HDL_TAP"TRUE";
"B \NAC \NWC"2;
"S \NAC"
BN"15"177;
%"TAP"
"1","(-2250,1675)","2","standard","I26";
;
CDS_LIB"standard"
BODY_TYPE"PLUMBING"
HDL_TAP"TRUE";
"B \NAC \NWC"22;
"S \NAC"
BN"1"53;
%"TAP"
"1","(3875,2050)","0","standard","I264";
;
CDS_LIB"standard"
BODY_TYPE"PLUMBING"
HDL_TAP"TRUE";
"B \NAC \NWC"4;
"S \NAC"
BN"3"152;
%"TAP"
"1","(-2250,1475)","2","standard","I27";
;
CDS_LIB"standard"
BODY_TYPE"PLUMBING"
HDL_TAP"TRUE";
"B \NAC \NWC"22;
"S \NAC"
BN"0"52;
%"TAP"
"1","(-2250,1875)","2","standard","I28";
;
CDS_LIB"standard"
BODY_TYPE"PLUMBING"
HDL_TAP"TRUE";
"B \NAC \NWC"22;
"S \NAC"
BN"2"57;
%"TAP"
"1","(-2350,-350)","2","standard","I3";
;
CDS_LIB"standard"
BODY_TYPE"PLUMBING"
HDL_TAP"TRUE";
"B \NAC \NWC"24;
"S \NAC"
BN"2"26;
%"TAP"
"1","(-2500,2025)","2","standard","I31";
;
CDS_LIB"standard"
BODY_TYPE"PLUMBING"
HDL_TAP"TRUE";
"B \NAC \NWC"23;
"S \NAC"
BN"3"55;
%"TAP"
"1","(-2500,2225)","2","standard","I32";
;
CDS_LIB"standard"
BODY_TYPE"PLUMBING"
HDL_TAP"TRUE";
"B \NAC \NWC"23;
"S \NAC"
BN"4"56;
%"TAP"
"1","(-2500,2425)","2","standard","I33";
;
CDS_LIB"standard"
BODY_TYPE"PLUMBING"
HDL_TAP"TRUE";
"B \NAC \NWC"23;
"S \NAC"
BN"5"59;
%"TAP"
"1","(-2250,2075)","2","standard","I34";
;
CDS_LIB"standard"
BODY_TYPE"PLUMBING"
HDL_TAP"TRUE";
"B \NAC \NWC"22;
"S \NAC"
BN"3"58;
%"TAP"
"1","(-2250,2275)","2","standard","I35";
;
CDS_LIB"standard"
BODY_TYPE"PLUMBING"
HDL_TAP"TRUE";
"B \NAC \NWC"22;
"S \NAC"
BN"4"38;
%"TAP"
"1","(-2250,2475)","2","standard","I36";
;
CDS_LIB"standard"
BODY_TYPE"PLUMBING"
HDL_TAP"TRUE";
"B \NAC \NWC"22;
"S \NAC"
BN"5"61;
%"TAP"
"1","(-2500,2625)","2","standard","I37";
;
CDS_LIB"standard"
BODY_TYPE"PLUMBING"
HDL_TAP"TRUE";
"B \NAC \NWC"23;
"S \NAC"
BN"6"60;
%"TAP"
"1","(-2500,2825)","2","standard","I38";
;
CDS_LIB"standard"
BODY_TYPE"PLUMBING"
HDL_TAP"TRUE";
"B \NAC \NWC"23;
"S \NAC"
BN"7"49;
%"TAP"
"1","(-2250,2675)","2","standard","I39";
;
CDS_LIB"standard"
BODY_TYPE"PLUMBING"
HDL_TAP"TRUE";
"B \NAC \NWC"22;
"S \NAC"
BN"6"62;
%"TAP"
"1","(-2100,-500)","2","standard","I4";
;
CDS_LIB"standard"
BODY_TYPE"PLUMBING"
HDL_TAP"TRUE";
"B \NAC \NWC"21;
"S \NAC"
BN"3"30;
%"TAP"
"1","(-2250,2875)","2","standard","I40";
;
CDS_LIB"standard"
BODY_TYPE"PLUMBING"
HDL_TAP"TRUE";
"B \NAC \NWC"22;
"S \NAC"
BN"7"63;
%"TAP"
"1","(-2475,3050)","2","standard","I41";
;
CDS_LIB"standard"
BODY_TYPE"PLUMBING"
HDL_TAP"TRUE";
"B \NAC \NWC"15;
"S \NAC"
BN"8"47;
%"TAP"
"1","(-2475,3250)","2","standard","I42";
;
CDS_LIB"standard"
BODY_TYPE"PLUMBING"
HDL_TAP"TRUE";
"B \NAC \NWC"15;
"S \NAC"
BN"9"48;
%"TAP"
"1","(-2475,3450)","2","standard","I43";
;
CDS_LIB"standard"
BODY_TYPE"PLUMBING"
HDL_TAP"TRUE";
"B \NAC \NWC"15;
"S \NAC"
BN"10"46;
%"TAP"
"1","(-2225,3100)","2","standard","I44";
;
CDS_LIB"standard"
BODY_TYPE"PLUMBING"
HDL_TAP"TRUE";
"B \NAC \NWC"16;
"S \NAC"
BN"8"45;
%"TAP"
"1","(-2225,3300)","2","standard","I45";
;
CDS_LIB"standard"
BODY_TYPE"PLUMBING"
HDL_TAP"TRUE";
"B \NAC \NWC"16;
"S \NAC"
BN"9"43;
%"TAP"
"1","(-2225,3500)","2","standard","I46";
;
CDS_LIB"standard"
BODY_TYPE"PLUMBING"
HDL_TAP"TRUE";
"B \NAC \NWC"16;
"S \NAC"
BN"10"44;
%"TAP"
"1","(-2475,3650)","2","standard","I47";
;
CDS_LIB"standard"
BODY_TYPE"PLUMBING"
HDL_TAP"TRUE";
"B \NAC \NWC"15;
"S \NAC"
BN"11"42;
%"TAP"
"1","(-2475,3850)","2","standard","I48";
;
CDS_LIB"standard"
BODY_TYPE"PLUMBING"
HDL_TAP"TRUE";
"B \NAC \NWC"15;
"S \NAC"
BN"12"41;
%"TAP"
"1","(-2225,3700)","2","standard","I49";
;
CDS_LIB"standard"
BODY_TYPE"PLUMBING"
HDL_TAP"TRUE";
"B \NAC \NWC"16;
"S \NAC"
BN"11"40;
%"TAP"
"1","(-2100,-300)","2","standard","I5";
;
CDS_LIB"standard"
BODY_TYPE"PLUMBING"
HDL_TAP"TRUE";
"B \NAC \NWC"21;
"S \NAC"
BN"2"28;
%"TAP"
"1","(-2225,3900)","2","standard","I50";
;
CDS_LIB"standard"
BODY_TYPE"PLUMBING"
HDL_TAP"TRUE";
"B \NAC \NWC"16;
"S \NAC"
BN"12"39;
%"Q_CAP_DIFFBUS"
"2","(-1375,50)","2","pure_quanta","I51";
;
LOCATION"C1996"
$SEC"1"
CDS_SEC"1"
VALUE"DIFF BUS_0.22UF"
CDS_LIB"pure_quanta"
CDS_LMAN_SYM_OUTLINE"-25,50,25,-50"
PIN_NAMES_ROTATE"TRUE"
VOLTAGE"6.3V"
MATERIAL"X6S"
PACK_TYPE"C0201"
TOLERANCE"20%"
PART_NUMBER"SP_CH4221MEE01";
"2"
$PN"2"37;
"1"
$PN"1"65;
%"Q_CAP_DIFFBUS"
"2","(-1375,100)","2","pure_quanta","I52";
;
LOCATION"C1995"
$SEC"1"
CDS_SEC"1"
VALUE"DIFF BUS_0.22UF"
VOLTAGE"6.3V"
PACK_TYPE"C0201"
TOLERANCE"20%"
MATERIAL"X6S"
CDS_LIB"pure_quanta"
CDS_LMAN_SYM_OUTLINE"-25,50,25,-50"
PIN_NAMES_ROTATE"TRUE"
PART_NUMBER"SP_CH4221MEE01";
"2"
$PN"2"64;
"1"
$PN"1"66;
%"Q_CAP_DIFFBUS"
"2","(-1525,1425)","2","pure_quanta","I53";
;
LOCATION"C1547"
$SEC"1"
CDS_SEC"1"
VALUE"DIFF BUS_0.22UF"
PIN_NAMES_ROTATE"TRUE"
CDS_LIB"pure_quanta"
CDS_LMAN_SYM_OUTLINE"-25,50,25,-50"
VOLTAGE"6.3V"
MATERIAL"X6S"
PACK_TYPE"C0201"
TOLERANCE"20%"
PART_NUMBER"SP_CH4221MEE01";
"2"
$PN"2"50;
"1"
$PN"1"67;
%"Q_CAP_DIFFBUS"
"2","(-1525,1475)","2","pure_quanta","I54";
;
LOCATION"C1546"
$SEC"1"
CDS_SEC"1"
VALUE"DIFF BUS_0.22UF"
PIN_NAMES_ROTATE"TRUE"
CDS_LIB"pure_quanta"
CDS_LMAN_SYM_OUTLINE"-25,50,25,-50"
VOLTAGE"6.3V"
MATERIAL"X6S"
PACK_TYPE"C0201"
TOLERANCE"20%"
PART_NUMBER"SP_CH4221MEE01";
"2"
$PN"2"52;
"1"
$PN"1"68;
%"Q_CAP_DIFFBUS"
"2","(-1525,1675)","2","pure_quanta","I55";
;
LOCATION"C1544"
$SEC"1"
CDS_SEC"1"
VALUE"DIFF BUS_0.22UF"
PIN_NAMES_ROTATE"TRUE"
CDS_LMAN_SYM_OUTLINE"-25,50,25,-50"
CDS_LIB"pure_quanta"
VOLTAGE"6.3V"
MATERIAL"X6S"
PACK_TYPE"C0201"
TOLERANCE"20%"
PART_NUMBER"SP_CH4221MEE01";
"2"
$PN"2"53;
"1"
$PN"1"71;
%"Q_CAP_DIFFBUS"
"2","(-1525,1625)","2","pure_quanta","I56";
;
LOCATION"C1545"
$SEC"1"
CDS_SEC"1"
VALUE"DIFF BUS_0.22UF"
PIN_NAMES_ROTATE"TRUE"
CDS_LIB"pure_quanta"
CDS_LMAN_SYM_OUTLINE"-25,50,25,-50"
VOLTAGE"6.3V"
MATERIAL"X6S"
PACK_TYPE"C0201"
TOLERANCE"20%"
PART_NUMBER"SP_CH4221MEE01";
"2"
$PN"2"51;
"1"
$PN"1"69;
%"Q_CAP_DIFFBUS"
"2","(-1525,1825)","2","pure_quanta","I57";
;
LOCATION"C1543"
$SEC"1"
CDS_SEC"1"
VALUE"DIFF BUS_0.22UF"
PIN_NAMES_ROTATE"TRUE"
CDS_LIB"pure_quanta"
CDS_LMAN_SYM_OUTLINE"-25,50,25,-50"
VOLTAGE"6.3V"
MATERIAL"X6S"
PACK_TYPE"C0201"
TOLERANCE"20%"
PART_NUMBER"SP_CH4221MEE01";
"2"
$PN"2"54;
"1"
$PN"1"70;
%"Q_CAP_DIFFBUS"
"2","(-1525,1875)","2","pure_quanta","I58";
;
LOCATION"C1542"
$SEC"1"
CDS_SEC"1"
VALUE"DIFF BUS_0.22UF"
PIN_NAMES_ROTATE"TRUE"
CDS_LIB"pure_quanta"
CDS_LMAN_SYM_OUTLINE"-25,50,25,-50"
VOLTAGE"6.3V"
MATERIAL"X6S"
PACK_TYPE"C0201"
TOLERANCE"20%"
PART_NUMBER"SP_CH4221MEE01";
"2"
$PN"2"57;
"1"
$PN"1"72;
%"TAP"
"1","(-825,100)","0","standard","I59";
;
CDS_LIB"standard"
BODY_TYPE"PLUMBING"
HDL_TAP"TRUE";
"B \NAC \NWC"19;
"S \NAC"
BN"0"66;
%"TAP"
"1","(-2100,-100)","2","standard","I6";
;
CDS_LIB"standard"
BODY_TYPE"PLUMBING"
HDL_TAP"TRUE";
"B \NAC \NWC"21;
"S \NAC"
BN"1"29;
%"TAP"
"1","(-625,50)","0","standard","I60";
;
CDS_LIB"standard"
BODY_TYPE"PLUMBING"
HDL_TAP"TRUE";
"B \NAC \NWC"20;
"S \NAC"
BN"0"65;
%"TAP"
"1","(-775,1425)","0","standard","I61";
;
CDS_LIB"standard"
BODY_TYPE"PLUMBING"
HDL_TAP"TRUE";
"B \NAC \NWC"17;
"S \NAC"
BN"0"67;
%"TAP"
"1","(-975,1475)","0","standard","I62";
;
CDS_LIB"standard"
BODY_TYPE"PLUMBING"
HDL_TAP"TRUE";
"B \NAC \NWC"18;
"S \NAC"
BN"0"68;
%"TAP"
"1","(-975,1675)","0","standard","I63";
;
CDS_LIB"standard"
BODY_TYPE"PLUMBING"
HDL_TAP"TRUE";
"B \NAC \NWC"18;
"S \NAC"
BN"1"71;
%"TAP"
"1","(-975,1875)","0","standard","I64";
;
CDS_LIB"standard"
BODY_TYPE"PLUMBING"
HDL_TAP"TRUE";
"B \NAC \NWC"18;
"S \NAC"
BN"2"72;
%"TAP"
"1","(-775,1625)","0","standard","I65";
;
CDS_LIB"standard"
BODY_TYPE"PLUMBING"
HDL_TAP"TRUE";
"B \NAC \NWC"17;
"S \NAC"
BN"1"69;
%"TAP"
"1","(-775,1825)","0","standard","I66";
;
CDS_LIB"standard"
BODY_TYPE"PLUMBING"
HDL_TAP"TRUE";
"B \NAC \NWC"17;
"S \NAC"
BN"2"70;
%"Q_CAP_DIFFBUS"
"2","(-1525,2025)","2","pure_quanta","I67";
;
LOCATION"C1541"
$SEC"1"
CDS_SEC"1"
VALUE"DIFF BUS_0.22UF"
PIN_NAMES_ROTATE"TRUE"
CDS_LMAN_SYM_OUTLINE"-25,50,25,-50"
CDS_LIB"pure_quanta"
VOLTAGE"6.3V"
MATERIAL"X6S"
PACK_TYPE"C0201"
TOLERANCE"20%"
PART_NUMBER"SP_CH4221MEE01";
"2"
$PN"2"55;
"1"
$PN"1"85;
%"Q_CAP_DIFFBUS"
"2","(-1525,2075)","2","pure_quanta","I68";
;
LOCATION"C1540"
$SEC"1"
CDS_SEC"1"
VALUE"DIFF BUS_0.22UF"
PIN_NAMES_ROTATE"TRUE"
CDS_LMAN_SYM_OUTLINE"-25,50,25,-50"
CDS_LIB"pure_quanta"
VOLTAGE"6.3V"
MATERIAL"X6S"
PACK_TYPE"C0201"
TOLERANCE"20%"
PART_NUMBER"SP_CH4221MEE01";
"2"
$PN"2"58;
"1"
$PN"1"89;
%"Q_CAP_DIFFBUS"
"2","(-1525,2225)","2","pure_quanta","I69";
;
LOCATION"C1539"
$SEC"1"
CDS_SEC"1"
VALUE"DIFF BUS_0.22UF"
PIN_NAMES_ROTATE"TRUE"
CDS_LIB"pure_quanta"
CDS_LMAN_SYM_OUTLINE"-25,50,25,-50"
VOLTAGE"6.3V"
MATERIAL"X6S"
PACK_TYPE"C0201"
TOLERANCE"20%"
PART_NUMBER"SP_CH4221MEE01";
"2"
$PN"2"56;
"1"
$PN"1"86;
%"Q_CAP_DIFFBUS"
"2","(-1375,-550)","2","pure_quanta","I7";
;
LOCATION"C1990"
$SEC"1"
CDS_SEC"1"
VALUE"DIFF BUS_0.22UF"
CDS_LMAN_SYM_OUTLINE"-25,50,25,-50"
CDS_LIB"pure_quanta"
TOLERANCE"20%"
PACK_TYPE"C0201"
MATERIAL"X6S"
VOLTAGE"6.3V"
PIN_NAMES_ROTATE"TRUE"
PART_NUMBER"SP_CH4221MEE01";
"2"
$PN"2"25;
"1"
$PN"1"31;
%"Q_CAP_DIFFBUS"
"2","(-1525,2275)","2","pure_quanta","I70";
;
LOCATION"C1538"
$SEC"1"
CDS_SEC"1"
VALUE"DIFF BUS_0.22UF"
PIN_NAMES_ROTATE"TRUE"
CDS_LIB"pure_quanta"
CDS_LMAN_SYM_OUTLINE"-25,50,25,-50"
VOLTAGE"6.3V"
MATERIAL"X6S"
PACK_TYPE"C0201"
TOLERANCE"20%"
PART_NUMBER"SP_CH4221MEE01";
"2"
$PN"2"38;
"1"
$PN"1"90;
%"Q_CAP_DIFFBUS"
"2","(-1525,2425)","2","pure_quanta","I71";
;
LOCATION"C1537"
$SEC"1"
CDS_SEC"1"
VALUE"DIFF BUS_0.22UF"
PIN_NAMES_ROTATE"TRUE"
CDS_LIB"pure_quanta"
CDS_LMAN_SYM_OUTLINE"-25,50,25,-50"
VOLTAGE"6.3V"
MATERIAL"X6S"
PACK_TYPE"C0201"
TOLERANCE"20%"
PART_NUMBER"SP_CH4221MEE01";
"2"
$PN"2"59;
"1"
$PN"1"87;
%"Q_CAP_DIFFBUS"
"2","(-1525,2475)","2","pure_quanta","I72";
;
LOCATION"C1536"
$SEC"1"
CDS_SEC"1"
VALUE"DIFF BUS_0.22UF"
PIN_NAMES_ROTATE"TRUE"
CDS_LIB"pure_quanta"
CDS_LMAN_SYM_OUTLINE"-25,50,25,-50"
VOLTAGE"6.3V"
MATERIAL"X6S"
PACK_TYPE"C0201"
TOLERANCE"20%"
PART_NUMBER"SP_CH4221MEE01";
"2"
$PN"2"61;
"1"
$PN"1"88;
%"Q_CAP_DIFFBUS"
"2","(-1525,2625)","2","pure_quanta","I73";
;
LOCATION"C1535"
$SEC"1"
CDS_SEC"1"
VALUE"DIFF BUS_0.22UF"
PIN_NAMES_ROTATE"TRUE"
CDS_LIB"pure_quanta"
CDS_LMAN_SYM_OUTLINE"-25,50,25,-50"
VOLTAGE"6.3V"
MATERIAL"X6S"
PACK_TYPE"C0201"
TOLERANCE"20%"
PART_NUMBER"SP_CH4221MEE01";
"2"
$PN"2"60;
"1"
$PN"1"92;
%"Q_CAP_DIFFBUS"
"2","(-1525,2675)","2","pure_quanta","I74";
;
LOCATION"C1534"
$SEC"1"
CDS_SEC"1"
VALUE"DIFF BUS_0.22UF"
PIN_NAMES_ROTATE"TRUE"
CDS_LIB"pure_quanta"
CDS_LMAN_SYM_OUTLINE"-25,50,25,-50"
VOLTAGE"6.3V"
MATERIAL"X6S"
PACK_TYPE"C0201"
TOLERANCE"20%"
PART_NUMBER"SP_CH4221MEE01";
"2"
$PN"2"62;
"1"
$PN"1"91;
%"Q_CAP_DIFFBUS"
"2","(-1525,2825)","2","pure_quanta","I75";
;
LOCATION"C1533"
$SEC"1"
CDS_SEC"1"
VALUE"DIFF BUS_0.22UF"
PIN_NAMES_ROTATE"TRUE"
CDS_LIB"pure_quanta"
CDS_LMAN_SYM_OUTLINE"-25,50,25,-50"
VOLTAGE"6.3V"
MATERIAL"X6S"
PACK_TYPE"C0201"
TOLERANCE"20%"
PART_NUMBER"SP_CH4221MEE01";
"2"
$PN"2"49;
"1"
$PN"1"84;
%"Q_CAP_DIFFBUS"
"2","(-1525,2875)","2","pure_quanta","I76";
;
LOCATION"C1532"
$SEC"1"
CDS_SEC"1"
VALUE"DIFF BUS_0.22UF"
PIN_NAMES_ROTATE"TRUE"
CDS_LMAN_SYM_OUTLINE"-25,50,25,-50"
CDS_LIB"pure_quanta"
VOLTAGE"6.3V"
MATERIAL"X6S"
PACK_TYPE"C0201"
TOLERANCE"20%"
PART_NUMBER"SP_CH4221MEE01";
"2"
$PN"2"63;
"1"
$PN"1"83;
%"Q_CAP_DIFFBUS"
"2","(-1500,3050)","2","pure_quanta","I77";
;
LOCATION"C1531"
$SEC"1"
CDS_SEC"1"
VALUE"DIFF BUS_0.22UF"
PIN_NAMES_ROTATE"TRUE"
VOLTAGE"6.3V"
MATERIAL"X6S"
PACK_TYPE"C0201"
TOLERANCE"20%"
CDS_LMAN_SYM_OUTLINE"-25,50,25,-50"
CDS_LIB"pure_quanta"
PART_NUMBER"SP_CH4221MEE01";
"2"
$PN"2"47;
"1"
$PN"1"82;
%"Q_CAP_DIFFBUS"
"2","(-1500,3100)","2","pure_quanta","I78";
;
LOCATION"C1530"
$SEC"1"
CDS_SEC"1"
VALUE"DIFF BUS_0.22UF"
PIN_NAMES_ROTATE"TRUE"
VOLTAGE"6.3V"
MATERIAL"X6S"
PACK_TYPE"C0201"
TOLERANCE"20%"
CDS_LMAN_SYM_OUTLINE"-25,50,25,-50"
CDS_LIB"pure_quanta"
PART_NUMBER"SP_CH4221MEE01";
"2"
$PN"2"45;
"1"
$PN"1"80;
%"Q_CAP_DIFFBUS"
"2","(-1500,3250)","2","pure_quanta","I79";
;
LOCATION"C1529"
$SEC"1"
CDS_SEC"1"
VALUE"DIFF BUS_0.22UF"
PIN_NAMES_ROTATE"TRUE"
VOLTAGE"6.3V"
MATERIAL"X6S"
PACK_TYPE"C0201"
TOLERANCE"20%"
CDS_LMAN_SYM_OUTLINE"-25,50,25,-50"
CDS_LIB"pure_quanta"
PART_NUMBER"SP_CH4221MEE01";
"2"
$PN"2"48;
"1"
$PN"1"81;
%"Q_CAP_DIFFBUS"
"2","(-1375,-500)","2","pure_quanta","I8";
;
LOCATION"C1989"
$SEC"1"
CDS_SEC"1"
VALUE"DIFF BUS_0.22UF"
CDS_LIB"pure_quanta"
CDS_LMAN_SYM_OUTLINE"-25,50,25,-50"
PIN_NAMES_ROTATE"TRUE"
VOLTAGE"6.3V"
MATERIAL"X6S"
PACK_TYPE"C0201"
TOLERANCE"20%"
PART_NUMBER"SP_CH4221MEE01";
"2"
$PN"2"30;
"1"
$PN"1"32;
%"Q_CAP_DIFFBUS"
"2","(-1500,3300)","2","pure_quanta","I80";
;
LOCATION"C1528"
$SEC"1"
CDS_SEC"1"
VALUE"DIFF BUS_0.22UF"
PIN_NAMES_ROTATE"TRUE"
VOLTAGE"6.3V"
MATERIAL"X6S"
PACK_TYPE"C0201"
TOLERANCE"20%"
CDS_LIB"pure_quanta"
CDS_LMAN_SYM_OUTLINE"-25,50,25,-50"
PART_NUMBER"SP_CH4221MEE01";
"2"
$PN"2"43;
"1"
$PN"1"77;
%"Q_CAP_DIFFBUS"
"2","(-1500,3500)","2","pure_quanta","I81";
;
LOCATION"C1526"
$SEC"1"
CDS_SEC"1"
VALUE"DIFF BUS_0.22UF"
PIN_NAMES_ROTATE"TRUE"
VOLTAGE"6.3V"
MATERIAL"X6S"
PACK_TYPE"C0201"
TOLERANCE"20%"
CDS_LMAN_SYM_OUTLINE"-25,50,25,-50"
CDS_LIB"pure_quanta"
PART_NUMBER"SP_CH4221MEE01";
"2"
$PN"2"44;
"1"
$PN"1"79;
%"Q_CAP_DIFFBUS"
"2","(-1500,3450)","2","pure_quanta","I82";
;
LOCATION"C1527"
$SEC"1"
CDS_SEC"1"
VALUE"DIFF BUS_0.22UF"
PIN_NAMES_ROTATE"TRUE"
VOLTAGE"6.3V"
MATERIAL"X6S"
PACK_TYPE"C0201"
TOLERANCE"20%"
CDS_LMAN_SYM_OUTLINE"-25,50,25,-50"
CDS_LIB"pure_quanta"
PART_NUMBER"SP_CH4221MEE01";
"2"
$PN"2"46;
"1"
$PN"1"78;
%"Q_CAP_DIFFBUS"
"2","(-1500,3650)","2","pure_quanta","I83";
;
LOCATION"C1525"
$SEC"1"
CDS_SEC"1"
VALUE"DIFF BUS_0.22UF"
PIN_NAMES_ROTATE"TRUE"
VOLTAGE"6.3V"
MATERIAL"X6S"
PACK_TYPE"C0201"
TOLERANCE"20%"
CDS_LIB"pure_quanta"
CDS_LMAN_SYM_OUTLINE"-25,50,25,-50"
PART_NUMBER"SP_CH4221MEE01";
"2"
$PN"2"42;
"1"
$PN"1"75;
%"Q_CAP_DIFFBUS"
"2","(-1500,3700)","2","pure_quanta","I84";
;
LOCATION"C1524"
$SEC"1"
CDS_SEC"1"
VALUE"DIFF BUS_0.22UF"
PIN_NAMES_ROTATE"TRUE"
VOLTAGE"6.3V"
MATERIAL"X6S"
PACK_TYPE"C0201"
TOLERANCE"20%"
CDS_LIB"pure_quanta"
CDS_LMAN_SYM_OUTLINE"-25,50,25,-50"
PART_NUMBER"SP_CH4221MEE01";
"2"
$PN"2"40;
"1"
$PN"1"76;
%"Q_CAP_DIFFBUS"
"2","(-1500,3850)","2","pure_quanta","I85";
;
LOCATION"C55"
$SEC"1"
CDS_SEC"1"
VALUE"DIFF BUS_0.22UF"
PIN_NAMES_ROTATE"TRUE"
VOLTAGE"6.3V"
MATERIAL"X6S"
PACK_TYPE"C0201"
TOLERANCE"20%"
CDS_LMAN_SYM_OUTLINE"-25,50,25,-50"
CDS_LIB"pure_quanta"
PART_NUMBER"SP_CH4221MEE01";
"2"
$PN"2"41;
"1"
$PN"1"73;
%"Q_CAP_DIFFBUS"
"2","(-1500,3900)","2","pure_quanta","I86";
;
LOCATION"C54"
$SEC"1"
CDS_SEC"1"
VALUE"DIFF BUS_0.22UF"
PIN_NAMES_ROTATE"TRUE"
VOLTAGE"6.3V"
MATERIAL"X6S"
PACK_TYPE"C0201"
TOLERANCE"20%"
CDS_LMAN_SYM_OUTLINE"-25,50,25,-50"
CDS_LIB"pure_quanta"
PART_NUMBER"SP_CH4221MEE01";
"2"
$PN"2"39;
"1"
$PN"1"74;
%"TAP"
"1","(-975,2075)","0","standard","I87";
;
CDS_LIB"standard"
BODY_TYPE"PLUMBING"
HDL_TAP"TRUE";
"B \NAC \NWC"18;
"S \NAC"
BN"3"89;
%"TAP"
"1","(-975,2475)","0","standard","I88";
;
CDS_LIB"standard"
BODY_TYPE"PLUMBING"
HDL_TAP"TRUE";
"B \NAC \NWC"18;
"S \NAC"
BN"5"88;
%"TAP"
"1","(-975,2275)","0","standard","I89";
;
CDS_LIB"standard"
BODY_TYPE"PLUMBING"
HDL_TAP"TRUE";
"B \NAC \NWC"18;
"S \NAC"
BN"4"90;
%"Q_CAP_DIFFBUS"
"2","(-1375,-350)","2","pure_quanta","I9";
;
LOCATION"C1992"
$SEC"1"
CDS_SEC"1"
VALUE"DIFF BUS_0.22UF"
CDS_LIB"pure_quanta"
CDS_LMAN_SYM_OUTLINE"-25,50,25,-50"
PIN_NAMES_ROTATE"TRUE"
VOLTAGE"6.3V"
MATERIAL"X6S"
PACK_TYPE"C0201"
TOLERANCE"20%"
PART_NUMBER"SP_CH4221MEE01";
"2"
$PN"2"26;
"1"
$PN"1"33;
%"TAP"
"1","(-775,2025)","0","standard","I90";
;
CDS_LIB"standard"
BODY_TYPE"PLUMBING"
HDL_TAP"TRUE";
"B \NAC \NWC"17;
"S \NAC"
BN"3"85;
%"TAP"
"1","(-775,2225)","0","standard","I91";
;
CDS_LIB"standard"
BODY_TYPE"PLUMBING"
HDL_TAP"TRUE";
"B \NAC \NWC"17;
"S \NAC"
BN"4"86;
%"TAP"
"1","(-775,2425)","0","standard","I92";
;
CDS_LIB"standard"
BODY_TYPE"PLUMBING"
HDL_TAP"TRUE";
"B \NAC \NWC"17;
"S \NAC"
BN"5"87;
%"TAP"
"1","(-975,2675)","0","standard","I93";
;
CDS_LIB"standard"
BODY_TYPE"PLUMBING"
HDL_TAP"TRUE";
"B \NAC \NWC"18;
"S \NAC"
BN"6"91;
%"TAP"
"1","(-975,2875)","0","standard","I94";
;
CDS_LIB"standard"
BODY_TYPE"PLUMBING"
HDL_TAP"TRUE";
"B \NAC \NWC"18;
"S \NAC"
BN"7"83;
%"TAP"
"1","(-775,2625)","0","standard","I95";
;
CDS_LIB"standard"
BODY_TYPE"PLUMBING"
HDL_TAP"TRUE";
"B \NAC \NWC"17;
"S \NAC"
BN"6"92;
%"TAP"
"1","(-775,2825)","0","standard","I96";
;
CDS_LIB"standard"
BODY_TYPE"PLUMBING"
HDL_TAP"TRUE";
"B \NAC \NWC"17;
"S \NAC"
BN"7"84;
%"TAP"
"1","(-950,3100)","0","standard","I97";
;
CDS_LIB"standard"
BODY_TYPE"PLUMBING"
HDL_TAP"TRUE";
"B \NAC \NWC"14;
"S \NAC"
BN"8"80;
%"TAP"
"1","(-950,3500)","0","standard","I98";
;
CDS_LIB"standard"
BODY_TYPE"PLUMBING"
HDL_TAP"TRUE";
"B \NAC \NWC"14;
"S \NAC"
BN"10"79;
%"TAP"
"1","(-950,3300)","0","standard","I99";
;
CDS_LIB"standard"
BODY_TYPE"PLUMBING"
HDL_TAP"TRUE";
"B \NAC \NWC"14;
"S \NAC"
BN"9"77;
END.
